G04 ================== begin FILE IDENTIFICATION RECORD ==================*
G04 Layout Name:  x887571-005_osp.brd*
G04 Film Name:    sst*
G04 File Format:  Gerber RS274X*
G04 File Origin:  Cadence Allegro 16.3-S036*
G04 Origin Date:  Thu Jul 03 00:06:57 2014*
G04 *
G04 Layer:  REF DES/SILKSCREEN_TOP*
G04 Layer:  PACKAGE GEOMETRY/SILKSCREEN_TOP*
G04 Layer:  DRAWING FORMAT/COMMON TEXT*
G04 Layer:  BOARD GEOMETRY/SILKSCREEN_TOP*
G04 *
G04 Offset:    (0.0000 0.0000)*
G04 Mirror:    No*
G04 Mode:      Positive*
G04 Rotation:  0*
G04 FullContactRelief:  No*
G04 UndefLineWidth:     4.0000*
G04 ================== end FILE IDENTIFICATION RECORD ====================*
%FSLAX25Y25*MOIN*%
%IR0*IPPOS*OFA0.00000B0.00000*MIA0B0*SFA1.00000B1.00000*%
%ADD10C,.01*%
%ADD11C,.012*%
%ADD12C,.013*%
%ADD13C,.015*%
%ADD14C,.004*%
%ADD15C,.005*%
%ADD16C,.006*%
%ADD17C,.007*%
%ADD18C,.008*%
G75*
%LPD*%
G75*
G54D10*
G01X-1184000Y-502500D02*
Y-512500D01*
G01X-1186683Y-502500D02*
X-1181317D01*
G01X-1176833Y-512500D02*
Y-502500D01*
X-1173917D01*
X-1172983Y-503000D01*
X-1172400Y-503667D01*
X-1172167Y-505000D01*
X-1172400Y-506333D01*
X-1173100Y-507167D01*
X-1173917Y-507667D01*
X-1176833D01*
G01X-1173917D02*
X-1172167Y-512500D01*
G01X-1167917D02*
X-1165000Y-502500D01*
X-1162083Y-512500D01*
G01X-1163133Y-509000D02*
X-1166867D01*
G01X-1155500Y-512500D02*
Y-508000D01*
X-1157833Y-502500D01*
G01X-1153167D02*
X-1155500Y-508000D01*
G01X-1135567Y-507167D02*
X-1135100Y-506667D01*
X-1134750Y-505834D01*
X-1134517Y-504667D01*
X-1134750Y-503667D01*
X-1135217Y-503000D01*
X-1136033Y-502500D01*
X-1139183D01*
Y-512500D01*
X-1135333D01*
X-1134517Y-511833D01*
X-1134050Y-510833D01*
X-1133817Y-509667D01*
X-1134050Y-508500D01*
X-1134750Y-507500D01*
X-1135567Y-507167D01*
X-1139183D01*
G01X-1129917Y-512500D02*
X-1127000Y-502500D01*
X-1124083Y-512500D01*
G01X-1125133Y-509000D02*
X-1128867D01*
G01X-1114933Y-503333D02*
X-1115633Y-502833D01*
X-1116450Y-502500D01*
X-1117383D01*
X-1118433Y-503000D01*
X-1119250Y-503833D01*
X-1119833Y-504833D01*
X-1120300Y-506500D01*
X-1120417Y-508000D01*
X-1120183Y-509500D01*
X-1119833Y-510500D01*
X-1119133Y-511500D01*
X-1118317Y-512167D01*
X-1117500Y-512500D01*
X-1116683D01*
X-1115867Y-512167D01*
X-1115167Y-511667D01*
X-1114583Y-511000D01*
G01X-1110567Y-512500D02*
Y-502500D01*
G01X-1106133D02*
X-1110567Y-508667D01*
G01X-1105433Y-512500D02*
X-1108583Y-505834D01*
G01X-1100833Y-512500D02*
Y-502500D01*
X-1098033D01*
X-1097100Y-503000D01*
X-1096400Y-504167D01*
X-1096167Y-505500D01*
X-1096400Y-506833D01*
X-1096983Y-507833D01*
X-1098033Y-508334D01*
X-1100833D01*
G01X-1091333Y-502500D02*
Y-512500D01*
X-1086667D01*
G01X-1082417D02*
X-1079500Y-502500D01*
X-1076583Y-512500D01*
G01X-1077633Y-509000D02*
X-1081367D01*
G01X-1072683Y-512500D02*
Y-502500D01*
X-1067317Y-512500D01*
Y-502500D01*
G01X-1058167Y-512500D02*
X-1062833D01*
Y-502500D01*
X-1058167D01*
G01X-1060033Y-507333D02*
X-1062833D01*
G01X-1043717Y-512500D02*
Y-502500D01*
X-1039283D01*
G01X-1040917Y-507333D02*
X-1043717D01*
G01X-1034917Y-512500D02*
X-1032000Y-502500D01*
X-1029083Y-512500D01*
G01X-1030133Y-509000D02*
X-1033867D01*
G01X-1021567Y-507167D02*
X-1021100Y-506667D01*
X-1020750Y-505834D01*
X-1020517Y-504667D01*
X-1020750Y-503667D01*
X-1021217Y-503000D01*
X-1022033Y-502500D01*
X-1025183D01*
Y-512500D01*
X-1021333D01*
X-1020517Y-511833D01*
X-1020050Y-510833D01*
X-1019817Y-509667D01*
X-1020050Y-508500D01*
X-1020750Y-507500D01*
X-1021567Y-507167D01*
X-1025183D01*
G01X-1002567D02*
X-1002100Y-506667D01*
X-1001750Y-505834D01*
X-1001517Y-504667D01*
X-1001750Y-503667D01*
X-1002217Y-503000D01*
X-1003033Y-502500D01*
X-1006183D01*
Y-512500D01*
X-1002333D01*
X-1001517Y-511833D01*
X-1001050Y-510833D01*
X-1000817Y-509667D01*
X-1001050Y-508500D01*
X-1001750Y-507500D01*
X-1002567Y-507167D01*
X-1006183D01*
G01X-985083Y-515833D02*
X-986250Y-514167D01*
X-986833Y-512500D01*
Y-505834D01*
X-986250Y-504167D01*
X-985083Y-502500D01*
G01X-975000Y-512500D02*
X-975933Y-512333D01*
X-976750Y-511667D01*
X-977450Y-510667D01*
X-977917Y-509500D01*
X-978150Y-508167D01*
Y-506833D01*
X-977917Y-505500D01*
X-977450Y-504333D01*
X-976750Y-503333D01*
X-975933Y-502667D01*
X-975000Y-502500D01*
X-974067Y-502667D01*
X-973250Y-503333D01*
X-972550Y-504333D01*
X-972083Y-505500D01*
X-971850Y-506833D01*
Y-508167D01*
X-972083Y-509500D01*
X-972550Y-510667D01*
X-973250Y-511667D01*
X-974067Y-512333D01*
X-975000Y-512500D01*
G01X-967950Y-511167D02*
X-967017Y-512000D01*
X-965967Y-512500D01*
X-965033D01*
X-964100Y-512000D01*
X-963400Y-511167D01*
X-963050Y-510000D01*
X-963283Y-508834D01*
X-963867Y-507833D01*
X-964917Y-507167D01*
X-966317Y-506833D01*
X-967133Y-506167D01*
X-967483Y-505000D01*
X-967250Y-503833D01*
X-966667Y-503000D01*
X-965850Y-502500D01*
X-965033D01*
X-964217Y-502833D01*
X-963517Y-503667D01*
G01X-958333Y-512500D02*
Y-502500D01*
X-955533D01*
X-954600Y-503000D01*
X-953900Y-504167D01*
X-953667Y-505500D01*
X-953900Y-506833D01*
X-954483Y-507833D01*
X-955533Y-508334D01*
X-958333D01*
G01X-945917Y-515833D02*
X-944750Y-514167D01*
X-944167Y-512500D01*
Y-505834D01*
X-944750Y-504167D01*
X-945917Y-502500D01*
G01X-926383Y-172500D02*
Y-163000D01*
X-923703D01*
X-922810Y-163475D01*
X-922140Y-164583D01*
X-921917Y-165850D01*
X-922140Y-167117D01*
X-922698Y-168067D01*
X-923703Y-168542D01*
X-926383D01*
G01X-912593Y-163792D02*
X-913263Y-163317D01*
X-914045Y-163000D01*
X-914938D01*
X-915943Y-163475D01*
X-916725Y-164267D01*
X-917283Y-165217D01*
X-917730Y-166800D01*
X-917842Y-168225D01*
X-917618Y-169650D01*
X-917283Y-170600D01*
X-916613Y-171550D01*
X-915832Y-172183D01*
X-915050Y-172500D01*
X-914268D01*
X-913487Y-172183D01*
X-912817Y-171708D01*
X-912258Y-171075D01*
G01X-905057Y-167433D02*
X-904610Y-166958D01*
X-904275Y-166167D01*
X-904052Y-165058D01*
X-904275Y-164108D01*
X-904722Y-163475D01*
X-905503Y-163000D01*
X-908518D01*
Y-172500D01*
X-904833D01*
X-904052Y-171867D01*
X-903605Y-170917D01*
X-903382Y-169808D01*
X-903605Y-168700D01*
X-904275Y-167750D01*
X-905057Y-167433D01*
X-908518D01*
G01X-889983Y-172500D02*
Y-163000D01*
X-887192D01*
X-886298Y-163475D01*
X-885740Y-164108D01*
X-885517Y-165375D01*
X-885740Y-166642D01*
X-886410Y-167433D01*
X-887192Y-167908D01*
X-889983D01*
G01X-887192D02*
X-885517Y-172500D01*
G01X-880325Y-168225D02*
X-876752D01*
X-877087Y-167117D01*
X-877645Y-166483D01*
X-878427Y-166167D01*
X-879208Y-166325D01*
X-879878Y-166800D01*
X-880325Y-167908D01*
X-880548Y-168859D01*
Y-169808D01*
X-880325Y-170758D01*
X-879767Y-171708D01*
X-879097Y-172342D01*
X-878315Y-172500D01*
X-877533Y-172183D01*
X-876752Y-171234D01*
G01X-871560Y-166167D02*
X-869550Y-172500D01*
X-867540Y-166167D01*
G01X-854142Y-172500D02*
X-851350Y-163000D01*
X-848558Y-172500D01*
G01X-849563Y-169175D02*
X-853137D01*
G01X-902000Y-470000D02*
Y-460000D01*
X-903400Y-462000D01*
G01Y-470000D02*
X-900600D01*
G01X-892500Y-470333D02*
X-892733Y-470167D01*
Y-469833D01*
X-892500Y-469667D01*
X-892267Y-469833D01*
Y-470167D01*
X-892500Y-470333D01*
G01Y-465834D02*
X-892733Y-465667D01*
Y-465333D01*
X-892500Y-465167D01*
X-892267Y-465333D01*
Y-465667D01*
X-892500Y-465834D01*
G01X-883000Y-470000D02*
Y-460000D01*
X-884400Y-462000D01*
G01Y-470000D02*
X-881600D01*
G01X-785060Y-472187D02*
X-784127Y-473020D01*
X-783077Y-473520D01*
X-782143D01*
X-781210Y-473020D01*
X-780510Y-472187D01*
X-780160Y-471020D01*
X-780393Y-469854D01*
X-780977Y-468853D01*
X-782027Y-468187D01*
X-783427Y-467853D01*
X-784243Y-467187D01*
X-784593Y-466020D01*
X-784360Y-464853D01*
X-783777Y-464020D01*
X-782960Y-463520D01*
X-782143D01*
X-781327Y-463853D01*
X-780627Y-464687D01*
G01X-775560Y-473520D02*
Y-463520D01*
G01X-770660D02*
Y-473520D01*
G01Y-468520D02*
X-775560D01*
G01X-766527Y-473520D02*
X-763610Y-463520D01*
X-760693Y-473520D01*
G01X-761743Y-470020D02*
X-765477D01*
G01X-757610Y-463520D02*
X-755977Y-473520D01*
X-754110Y-463520D01*
X-752243Y-473520D01*
X-750610Y-463520D01*
G01X-668067Y-470500D02*
X-667367Y-471667D01*
X-666433Y-472333D01*
X-665383Y-472500D01*
X-664450Y-472333D01*
X-663517Y-471500D01*
X-662933Y-470500D01*
X-662817Y-469500D01*
X-663050Y-468334D01*
X-663867Y-467500D01*
X-664683Y-467167D01*
X-665733D01*
G01X-664683D02*
X-663983Y-466667D01*
X-663400Y-465834D01*
X-663167Y-464833D01*
X-663400Y-463833D01*
X-663983Y-463000D01*
X-665033Y-462500D01*
X-666083Y-462667D01*
X-667133Y-463333D01*
G01X-656000Y-462500D02*
X-656933Y-462833D01*
X-657633Y-463667D01*
X-658100Y-464667D01*
X-658450Y-466000D01*
X-658567Y-467500D01*
X-658450Y-469000D01*
X-658100Y-470333D01*
X-657633Y-471334D01*
X-656933Y-472167D01*
X-656000Y-472500D01*
X-655067Y-472167D01*
X-654367Y-471334D01*
X-653900Y-470333D01*
X-653550Y-469000D01*
X-653433Y-467500D01*
X-653550Y-466000D01*
X-653900Y-464667D01*
X-654367Y-463667D01*
X-655067Y-462833D01*
X-656000Y-462500D01*
G01X-648017Y-469167D02*
X-644983D01*
G01X-639917Y-472500D02*
X-637000Y-462500D01*
X-634083Y-472500D01*
G01X-635133Y-469000D02*
X-638867D01*
G01X-629833Y-472500D02*
Y-462500D01*
X-627033D01*
X-626100Y-463000D01*
X-625400Y-464167D01*
X-625167Y-465500D01*
X-625400Y-466833D01*
X-625983Y-467833D01*
X-627033Y-468334D01*
X-629833D01*
G01X-620333Y-472500D02*
Y-462500D01*
X-617417D01*
X-616483Y-463000D01*
X-615900Y-463667D01*
X-615667Y-465000D01*
X-615900Y-466333D01*
X-616600Y-467167D01*
X-617417Y-467667D01*
X-620333D01*
G01X-617417D02*
X-615667Y-472500D01*
G01X-610017Y-469167D02*
X-606983D01*
G01X-599000Y-472500D02*
Y-462500D01*
X-600400Y-464500D01*
G01Y-472500D02*
X-597600D01*
G01X-588100D02*
Y-462500D01*
X-592417Y-469667D01*
X-586583D01*
G54D11*
G01X-1174900Y-473500D02*
X-1171300Y-466100D01*
X-1171800Y-465700D01*
X-1175900Y-473200D01*
X-1176200Y-471200D01*
X-1172500Y-465400D01*
X-1175700Y-471300D01*
X-1176500Y-469800D01*
X-1172900Y-464900D01*
X-1173600Y-451800D01*
X-1173700Y-449900D01*
X-1182100D01*
X-1187400Y-473000D01*
X-1182400D01*
X-1177800Y-456000D01*
X-1177000Y-455900D01*
X-1176100Y-468500D01*
X-1173700Y-464500D01*
X-1174600Y-450800D01*
X-1181500Y-450900D01*
X-1186400Y-472100D01*
X-1183100D01*
X-1178300Y-454800D01*
X-1176600Y-455000D01*
X-1175500Y-466300D01*
X-1174600Y-464300D01*
X-1175400Y-451700D01*
X-1181000Y-451800D01*
X-1185300Y-471300D01*
X-1183800Y-471400D01*
X-1179000Y-454300D01*
X-1176200D01*
X-1175200Y-462200D01*
X-1176200Y-452500D01*
X-1180500Y-452800D01*
X-1184300Y-470600D01*
X-1179700Y-453400D01*
X-1176800D01*
G01X-1182820Y-448900D02*
X-1188360Y-473900D01*
X-1181580D01*
X-1177300Y-456700D01*
X-1176920Y-473900D01*
X-1172260D01*
X-1163400Y-456920D01*
X-1167240Y-473900D01*
X-1160380D01*
X-1154840Y-448900D01*
X-1164540D01*
X-1172540Y-464820D01*
X-1172880Y-448900D01*
X-1182820D01*
G01X-1155800Y-449500D02*
X-1161100Y-472900D01*
X-1166100Y-473000D01*
X-1166000Y-471900D01*
X-1161800Y-472100D01*
X-1161300Y-471000D01*
X-1165900Y-471100D01*
X-1165700Y-470000D01*
X-1161300D01*
X-1160800Y-469200D01*
X-1165300Y-469100D01*
X-1165200Y-468100D01*
X-1160700D01*
X-1160400Y-467100D01*
X-1165100Y-467200D01*
X-1164900Y-466300D01*
X-1160300Y-466200D01*
X-1160000Y-465200D01*
X-1164700Y-465300D01*
X-1164400Y-464200D01*
X-1159700Y-464300D01*
X-1159300Y-463100D01*
X-1164700Y-463500D01*
X-1164000Y-462500D01*
X-1159500Y-462600D01*
X-1159000Y-461700D01*
X-1163900D01*
X-1163600Y-460600D01*
X-1159100Y-460800D01*
X-1158800Y-459900D01*
X-1163200D01*
X-1163100Y-459200D01*
X-1158800D01*
X-1158300Y-458500D01*
X-1163000Y-458400D01*
X-1162900Y-457800D01*
X-1158400Y-457900D01*
X-1158200Y-457200D01*
X-1162500Y-457000D01*
X-1163100Y-456500D01*
X-1157800D01*
X-1157500Y-455500D01*
X-1156600Y-449800D01*
X-1164000D01*
X-1164500Y-450700D01*
X-1157600D01*
X-1157800Y-451700D01*
X-1165000Y-451600D01*
X-1165400Y-452400D01*
X-1157900Y-452500D01*
X-1157800Y-453500D01*
X-1165900Y-453200D01*
X-1166200Y-453900D01*
X-1158000Y-454300D01*
X-1158300Y-455300D01*
X-1166600Y-454800D01*
X-1158900Y-455900D01*
X-1167000Y-455600D01*
X-1163500Y-456400D01*
X-1167300Y-456300D01*
X-1171700Y-465200D01*
X-1169200Y-466400D01*
X-1164500Y-457200D01*
X-1166900Y-457100D01*
X-1170600Y-465200D01*
X-1169500Y-465500D01*
X-1166000Y-457800D01*
G01X-1170300Y-466300D02*
X-1174000Y-473600D01*
G01X-1169500Y-466900D02*
X-1172800Y-473000D01*
G01X-1152800Y-456400D02*
X-1156600Y-473100D01*
X-1152200Y-473000D01*
X-1148300Y-456600D01*
X-1149500D01*
X-1152900Y-472000D01*
X-1155600Y-472300D01*
X-1152100Y-456500D01*
X-1150400Y-456400D01*
X-1153600Y-471200D01*
X-1154500Y-471400D01*
X-1151400Y-457200D01*
G01X-1153420Y-455700D02*
X-1157540Y-473900D01*
X-1151380D01*
X-1147440Y-455700D01*
X-1153420D01*
G01X-1151600Y-450100D02*
X-1146700Y-450000D01*
X-1147000Y-451000D01*
X-1151700D01*
G01X-1152020Y-448900D02*
X-1152660Y-451900D01*
X-1146380D01*
X-1145740Y-448900D01*
X-1152020D01*
G01X-1129400Y-468900D02*
X-1131800Y-471900D01*
X-1136500Y-473700D01*
X-1142100Y-473600D01*
X-1144600Y-472300D01*
X-1145800Y-471000D01*
X-1146400Y-469500D01*
X-1146700Y-467600D01*
X-1146500Y-464600D01*
X-1145400Y-461200D01*
X-1143500Y-459100D01*
X-1140200Y-456900D01*
X-1136100Y-456200D01*
X-1132300Y-456400D01*
X-1129400Y-457900D01*
X-1127500Y-460900D01*
X-1132500Y-461000D01*
X-1133400Y-459200D01*
X-1135100Y-458100D01*
X-1136800Y-458000D01*
X-1138600Y-458900D01*
X-1140300Y-460700D01*
X-1141800Y-463600D01*
X-1142400Y-466600D01*
X-1141500Y-470400D01*
X-1140200Y-471500D01*
X-1138300Y-471600D01*
X-1136300Y-471400D01*
X-1134500Y-469100D01*
X-1130300Y-469000D01*
X-1132500Y-471200D01*
X-1134900Y-472000D01*
X-1137200Y-472800D01*
X-1142300Y-472700D01*
X-1144900Y-470600D01*
X-1145800Y-467400D01*
X-1145500Y-465100D01*
X-1144700Y-462000D01*
X-1143300Y-460200D01*
X-1139800Y-457700D01*
X-1135400Y-457000D01*
X-1131300Y-457600D01*
X-1128800Y-460100D01*
X-1132100D01*
X-1134300Y-457900D01*
X-1130100Y-458800D01*
X-1129500Y-459400D01*
X-1132600Y-459000D01*
G01X-1133300Y-461900D02*
Y-461420D01*
X-1133640Y-460240D01*
X-1134300Y-459200D01*
X-1135200Y-458900D01*
X-1136580D01*
X-1138060Y-459820D01*
X-1139360Y-461000D01*
X-1140240Y-462220D01*
X-1140880Y-463920D01*
X-1141300Y-465380D01*
X-1141500Y-467060D01*
Y-468020D01*
X-1141020Y-469220D01*
X-1139780Y-470700D01*
X-1137160D01*
X-1135840Y-469500D01*
X-1134980Y-468200D01*
X-1134940Y-468100D01*
X-1128180D01*
X-1128240Y-468240D01*
X-1128840Y-469340D01*
X-1129020Y-469800D01*
X-1129740Y-470700D01*
X-1130500Y-471460D01*
X-1131660Y-472420D01*
X-1132820Y-473200D01*
X-1133740Y-473740D01*
X-1136380Y-474500D01*
X-1141640D01*
X-1142540Y-474320D01*
X-1144220Y-473760D01*
X-1144900Y-473240D01*
X-1146240Y-471900D01*
X-1146780Y-471180D01*
X-1146940Y-470880D01*
X-1147320Y-469660D01*
X-1147500Y-468640D01*
Y-464780D01*
X-1146940Y-462540D01*
X-1146380Y-461580D01*
X-1145980Y-460780D01*
X-1145420Y-459880D01*
X-1143700Y-458140D01*
X-1142740Y-457380D01*
X-1142000Y-456820D01*
X-1140240Y-456040D01*
X-1139500Y-455660D01*
X-1138800Y-455480D01*
X-1137260Y-455300D01*
X-1134320D01*
X-1132020Y-455500D01*
X-1130940Y-455860D01*
X-1130580Y-456020D01*
X-1129260Y-456780D01*
X-1128940Y-457100D01*
X-1127820Y-458420D01*
X-1127060Y-460300D01*
X-1126900Y-460800D01*
Y-461900D01*
X-1133300D01*
G01X-1137900Y-458000D02*
X-1140300Y-459100D01*
X-1142500Y-460900D01*
X-1143900Y-462600D01*
X-1144800Y-467600D01*
X-1144200Y-470000D01*
X-1141000Y-472300D01*
X-1136400Y-472200D01*
X-1131600Y-469600D01*
X-1135400Y-470400D01*
X-1141100Y-471400D01*
X-1142100Y-470700D01*
X-1142700Y-469000D01*
X-1143100Y-467100D01*
X-1142700Y-464100D01*
X-1140500Y-459900D01*
X-1143400Y-463700D01*
X-1143600Y-465700D01*
X-1143900Y-467700D01*
X-1143000Y-469900D01*
G01X-1113500Y-459200D02*
X-1123500Y-459300D01*
X-1123700Y-460100D01*
X-1114300Y-460000D01*
X-1116500Y-460800D01*
X-1124200Y-461000D01*
X-1124400Y-461900D01*
X-1117600Y-461800D01*
X-1118800Y-462800D01*
X-1124500Y-462700D01*
X-1124600Y-463600D01*
X-1119300Y-463700D01*
X-1120100Y-464800D01*
X-1125000Y-464600D01*
Y-465500D01*
X-1120600Y-465700D01*
X-1120800Y-466700D01*
X-1125300Y-466500D01*
X-1125500Y-467400D01*
X-1121000Y-467600D01*
X-1121200Y-468700D01*
X-1125600Y-468400D01*
X-1125900Y-469100D01*
X-1121500Y-469500D01*
X-1121700Y-470700D01*
X-1126100Y-470000D01*
X-1126200Y-470700D01*
X-1121900Y-471200D01*
X-1122100Y-472000D01*
X-1126300Y-471700D01*
X-1126700Y-472300D01*
X-1122100Y-472700D01*
X-1122200Y-473100D01*
X-1126800Y-473200D01*
G01X-1114060Y-460760D02*
X-1114840Y-460920D01*
X-1115740Y-461140D01*
X-1116880Y-461820D01*
X-1117700Y-462640D01*
X-1118620Y-463340D01*
X-1118840Y-464020D01*
X-1119440Y-464820D01*
X-1119660Y-465480D01*
X-1120060Y-466280D01*
X-1120280Y-466960D01*
X-1120480Y-468360D01*
X-1120680Y-468940D01*
X-1120880Y-469940D01*
X-1121080Y-470540D01*
X-1121700Y-472980D01*
X-1121820Y-473900D01*
X-1127640D01*
X-1126920Y-471060D01*
X-1126720Y-470440D01*
X-1126500Y-468800D01*
X-1126320Y-467860D01*
X-1126120Y-467260D01*
X-1125920Y-466260D01*
X-1125720Y-465660D01*
X-1125300Y-464000D01*
X-1125120Y-462220D01*
X-1124920Y-461660D01*
X-1124720Y-460660D01*
X-1124520Y-460060D01*
X-1123720Y-456800D01*
X-1123580Y-455700D01*
X-1117880D01*
X-1118100Y-456160D01*
Y-458740D01*
X-1116500Y-457160D01*
X-1115780Y-456620D01*
X-1114680Y-456060D01*
X-1113560Y-455680D01*
X-1112460Y-455500D01*
X-1111720D01*
X-1112460Y-458440D01*
X-1114060Y-460760D01*
G01X-1123100Y-456500D02*
X-1118900Y-456600D01*
X-1118800Y-457600D01*
X-1123100Y-457500D01*
X-1123300Y-458500D01*
X-1113100Y-458400D01*
X-1112600Y-456400D01*
X-1116100Y-457600D01*
X-1113500D01*
G01X-1105100Y-471100D02*
X-1104060D01*
X-1103780Y-470820D01*
X-1103200Y-470640D01*
X-1102080Y-469740D01*
X-1100800Y-468240D01*
X-1100380Y-467400D01*
X-1100180Y-467100D01*
X-1099960Y-466660D01*
X-1099540Y-465720D01*
X-1099320Y-465060D01*
X-1099100Y-464180D01*
Y-461220D01*
X-1099360Y-460200D01*
X-1099660Y-459900D01*
X-1100700Y-458640D01*
X-1101220Y-458300D01*
X-1103340D01*
X-1103700Y-458640D01*
X-1105300Y-459840D01*
X-1105760Y-460320D01*
X-1106180Y-460940D01*
X-1107060Y-462020D01*
X-1107260Y-462880D01*
X-1107660Y-463660D01*
X-1108100Y-465000D01*
Y-468640D01*
X-1107620Y-469600D01*
X-1107140Y-470340D01*
X-1105980Y-471100D01*
X-1105100D01*
G01X-1112540Y-460460D02*
X-1110680Y-458140D01*
X-1109940Y-457580D01*
X-1109000Y-456840D01*
X-1108480Y-456660D01*
X-1107940Y-456400D01*
X-1107740Y-456200D01*
X-1107480Y-456060D01*
X-1106880Y-455860D01*
X-1106480Y-455660D01*
X-1105960Y-455480D01*
X-1104600Y-455300D01*
X-1103440Y-455100D01*
X-1100940D01*
X-1098240Y-455480D01*
X-1097720Y-455660D01*
X-1097020Y-456020D01*
X-1096180Y-456640D01*
X-1095620Y-456820D01*
X-1095540Y-456900D01*
X-1094200Y-458440D01*
X-1093660Y-459520D01*
X-1093460Y-460100D01*
X-1093100Y-461020D01*
Y-464400D01*
X-1093420Y-465360D01*
X-1094300Y-465520D01*
X-1094720Y-465740D01*
X-1095320Y-465940D01*
X-1096120Y-466340D01*
X-1096720Y-466540D01*
X-1097100Y-466720D01*
X-1098100Y-466920D01*
X-1098520Y-467140D01*
X-1099160Y-467360D01*
X-1101180Y-468700D01*
X-1094660D01*
X-1095220Y-469800D01*
X-1095560Y-470320D01*
X-1097480Y-472220D01*
X-1099940Y-473740D01*
X-1102580Y-474500D01*
X-1108800D01*
X-1109300Y-474340D01*
X-1111220Y-473560D01*
X-1111720Y-473240D01*
X-1113240Y-471720D01*
X-1113560Y-471240D01*
X-1113760Y-470660D01*
X-1114140Y-469980D01*
X-1114320Y-469120D01*
X-1114500Y-468680D01*
Y-464980D01*
X-1114320Y-464260D01*
X-1114140Y-463720D01*
X-1113940Y-463320D01*
X-1113720Y-462660D01*
X-1113560Y-462000D01*
X-1111880Y-460320D01*
X-1112540Y-460460D01*
G01X-1099300Y-466400D02*
X-1093800Y-464400D01*
X-1093900Y-461100D01*
X-1094800Y-459000D01*
X-1096800Y-457300D01*
X-1100000Y-456100D01*
X-1102800Y-455900D01*
X-1106300Y-456300D01*
X-1109600Y-458100D01*
X-1111400Y-460500D01*
X-1112900Y-462600D01*
X-1113600Y-465600D01*
X-1113500Y-469100D01*
X-1112100Y-471900D01*
X-1109600Y-473300D01*
X-1105700Y-473800D01*
X-1101000Y-473400D01*
X-1098200Y-471800D01*
X-1096600Y-470100D01*
X-1096000Y-469500D01*
X-1100800Y-469700D01*
X-1102300Y-471100D01*
X-1097900Y-470400D01*
X-1100300Y-471800D01*
X-1103200Y-471400D01*
X-1100600Y-472600D01*
X-1103000D01*
X-1103700Y-471900D01*
X-1103400Y-473000D01*
X-1104600Y-471900D01*
X-1106200D01*
X-1104100Y-473100D01*
X-1107200Y-472700D01*
X-1110100Y-472100D01*
X-1111500Y-470900D01*
X-1112600Y-468600D01*
X-1112700Y-466000D01*
X-1112400Y-463700D01*
X-1111400Y-461600D01*
X-1109600Y-459500D01*
X-1108100Y-458200D01*
X-1105900Y-457200D01*
X-1102200Y-456700D01*
X-1099600Y-457300D01*
X-1097000Y-458400D01*
X-1095500Y-459500D01*
X-1094600Y-461900D01*
X-1094500Y-463900D01*
X-1098800Y-465200D01*
X-1098600Y-464000D01*
X-1095100Y-463100D01*
X-1095300Y-462000D01*
X-1098500Y-463000D01*
X-1098600Y-461700D01*
X-1095600Y-461300D01*
X-1095900Y-460200D01*
X-1098400Y-460700D01*
X-1098900Y-459900D01*
X-1096600Y-459400D01*
X-1097100Y-458900D01*
X-1099400Y-459000D01*
X-1098800Y-458500D01*
X-1100600Y-458000D01*
X-1102400Y-457400D01*
X-1104200Y-457500D01*
X-1106200Y-458100D01*
X-1107900Y-459000D01*
X-1110500Y-462200D01*
X-1111800Y-464800D01*
Y-467700D01*
X-1110700Y-470300D01*
X-1108700Y-472000D01*
X-1106600Y-471900D01*
X-1107900Y-470300D01*
X-1108900Y-468700D01*
Y-465500D01*
X-1107900Y-462300D01*
X-1106500Y-459900D01*
X-1104100Y-458200D01*
X-1108000Y-460000D01*
X-1108100Y-461500D01*
X-1108700Y-461200D01*
X-1110300Y-463600D01*
X-1111000Y-466000D01*
X-1110700Y-468100D01*
X-1109500Y-470600D01*
X-1107700Y-471400D01*
X-1109300Y-469100D01*
X-1109800Y-467600D01*
X-1108600Y-462200D01*
X-1110400Y-466800D01*
G01X-1113600Y-460900D02*
X-1112100Y-459000D01*
G01X-1093100Y-469400D02*
X-1087900Y-469700D01*
X-1086500Y-471400D01*
X-1083400Y-472300D01*
X-1081000Y-472000D01*
X-1079300Y-470600D01*
X-1079000Y-468900D01*
X-1079500Y-467700D01*
X-1080300Y-466600D01*
X-1081800Y-466000D01*
X-1083300Y-465500D01*
X-1085300Y-465000D01*
X-1087900Y-464000D01*
X-1089100Y-463200D01*
X-1089800Y-461000D01*
X-1089500Y-459000D01*
X-1088600Y-457700D01*
X-1086500Y-456700D01*
X-1084600Y-456100D01*
X-1081900Y-455900D01*
X-1079900Y-455800D01*
X-1076900Y-456300D01*
X-1075000Y-457000D01*
X-1073700Y-458000D01*
X-1073300Y-459400D01*
X-1077600Y-459500D01*
X-1078100Y-458800D01*
X-1074300Y-458500D01*
X-1074600Y-457800D01*
X-1078200Y-458200D01*
X-1076000Y-457400D01*
X-1079100Y-457700D01*
X-1077100Y-456900D01*
X-1080100Y-457300D01*
X-1079200Y-456600D01*
X-1083100Y-456800D01*
X-1080600Y-457300D01*
X-1083400Y-457700D01*
X-1083600Y-457000D01*
X-1087900Y-458400D01*
X-1084000Y-458100D01*
X-1088600Y-459100D01*
X-1088800Y-461500D01*
X-1087700Y-463600D01*
X-1084400Y-464300D01*
X-1081200Y-465400D01*
X-1078800Y-467300D01*
X-1078300Y-470500D01*
X-1079900Y-472600D01*
X-1083500Y-473300D01*
X-1085600Y-472600D01*
X-1088800Y-470500D01*
X-1092600Y-470200D01*
X-1092100Y-471800D01*
X-1091700Y-471300D01*
X-1089300Y-471500D01*
X-1091300Y-472300D01*
X-1088700Y-471600D01*
X-1084000Y-473500D01*
X-1089100D01*
X-1091000Y-472900D01*
X-1087200Y-472800D01*
X-1082700Y-473700D01*
X-1079000Y-473600D01*
X-1076500Y-472300D01*
X-1074700Y-470600D01*
X-1074300Y-467300D01*
X-1074800Y-465300D01*
X-1078800Y-463600D01*
X-1081600Y-462900D01*
X-1083400Y-462500D01*
X-1084800Y-461500D01*
X-1085000Y-458900D01*
X-1088100Y-459800D01*
X-1087200Y-462700D01*
X-1085000Y-463400D01*
X-1082000Y-464100D01*
X-1079600Y-465100D01*
X-1078200Y-466500D01*
X-1077700Y-468500D01*
X-1077500Y-470100D01*
X-1079200Y-472800D01*
X-1076800Y-471400D01*
X-1075300Y-470000D01*
X-1077300Y-470900D01*
X-1075000Y-468800D01*
X-1075200Y-466100D01*
X-1082700Y-462700D01*
X-1084200Y-462900D01*
X-1086600Y-461800D01*
X-1087200Y-460300D01*
X-1085800Y-459800D01*
X-1086600Y-461000D01*
X-1085300Y-460400D01*
X-1085600Y-461400D01*
X-1076700Y-466500D01*
X-1075900Y-467100D01*
X-1075700Y-468400D01*
X-1076800Y-469500D01*
X-1077800Y-466200D01*
X-1075900Y-468800D01*
G01X-1093780Y-468700D02*
X-1087100D01*
Y-469740D01*
X-1086800Y-470060D01*
X-1086520Y-470600D01*
X-1085820Y-470820D01*
X-1085660Y-471000D01*
X-1085120Y-471260D01*
X-1084400Y-471500D01*
X-1082360D01*
X-1080540Y-470600D01*
X-1080100Y-470140D01*
Y-469780D01*
X-1079840Y-469380D01*
X-1080380Y-467740D01*
X-1081440Y-466940D01*
X-1082560Y-466720D01*
X-1085740Y-465920D01*
X-1086940Y-465520D01*
X-1087600Y-465360D01*
X-1087740Y-465200D01*
X-1088540Y-464800D01*
X-1089140Y-464200D01*
X-1089540Y-464000D01*
X-1089800Y-463740D01*
X-1090000Y-463340D01*
X-1090180Y-463180D01*
X-1090500Y-462200D01*
Y-459800D01*
X-1090320Y-459260D01*
X-1090140Y-458500D01*
X-1090000Y-458260D01*
X-1089000Y-457260D01*
X-1088860Y-456940D01*
X-1085920Y-455480D01*
X-1083620Y-455100D01*
X-1082060Y-454900D01*
X-1080520D01*
X-1078580Y-455100D01*
X-1076240Y-455480D01*
X-1075120Y-455860D01*
X-1074800Y-456020D01*
X-1073680Y-456760D01*
X-1073160Y-457300D01*
X-1072620Y-458020D01*
X-1072500Y-458240D01*
Y-460300D01*
X-1078500D01*
Y-459200D01*
X-1079580Y-458380D01*
X-1080160Y-458100D01*
X-1082380D01*
X-1083280Y-458360D01*
X-1084020Y-458940D01*
X-1084340Y-459900D01*
X-1084060Y-460720D01*
X-1083740Y-461340D01*
X-1081860Y-462280D01*
X-1079400Y-462500D01*
X-1078660Y-462680D01*
X-1078100Y-462860D01*
X-1076500Y-463460D01*
X-1075320Y-463860D01*
X-1075060Y-464000D01*
X-1073820Y-465220D01*
X-1073480Y-466260D01*
X-1073300Y-467160D01*
Y-468420D01*
X-1073860Y-470700D01*
X-1074000Y-470960D01*
X-1075140Y-472300D01*
X-1075280Y-472440D01*
X-1076600Y-473380D01*
X-1077320Y-473740D01*
X-1079600Y-474500D01*
X-1088240D01*
X-1089160Y-474320D01*
X-1089920Y-474120D01*
X-1090860Y-473760D01*
X-1091560Y-473400D01*
X-1092700Y-472460D01*
X-1093180Y-471980D01*
X-1093340Y-471480D01*
X-1093520Y-471100D01*
X-1093700Y-470320D01*
X-1093780Y-468700D01*
G01X-1095100D02*
X-1092800D01*
G01X-1058300Y-469400D02*
X-1055400Y-467100D01*
X-1053900Y-463700D01*
X-1054400Y-461200D01*
X-1055900Y-459900D01*
X-1054800Y-463500D01*
X-1055400Y-463600D01*
X-1054600Y-464500D01*
X-1055700D01*
X-1055400Y-465300D01*
X-1056200Y-466800D01*
G01X-1059300Y-457700D02*
X-1059100Y-455600D01*
X-1055200Y-456300D01*
X-1052700Y-457900D01*
X-1051100Y-460800D01*
X-1050900Y-465200D01*
X-1052900Y-469400D01*
X-1055300Y-471900D01*
X-1059000Y-473500D01*
X-1066000D01*
X-1068000Y-471900D01*
X-1070200Y-468700D01*
X-1070600Y-464500D01*
X-1069000Y-460500D01*
X-1066000Y-457500D01*
X-1063000Y-456500D01*
X-1059200Y-456000D01*
X-1053000Y-458500D01*
X-1052000Y-461500D01*
Y-465700D01*
X-1053400Y-468600D01*
X-1055700Y-471000D01*
X-1058900Y-472600D01*
X-1063700Y-473000D01*
X-1065900Y-473600D01*
X-1068300Y-472900D01*
X-1070600Y-469300D01*
X-1065100Y-472600D01*
X-1060800Y-472200D01*
X-1057200Y-470700D01*
X-1055200Y-469100D01*
X-1053300Y-466500D01*
X-1052500Y-463400D01*
X-1052900Y-460100D01*
X-1057000Y-457400D01*
X-1058700Y-457200D01*
X-1057000Y-458500D01*
X-1055100Y-459800D01*
X-1053800Y-460900D01*
X-1053400Y-463100D01*
X-1053600Y-465600D01*
X-1054800Y-467500D01*
X-1056400Y-469200D01*
X-1058500Y-470200D01*
X-1060200Y-470700D01*
X-1061500Y-471400D01*
X-1063300Y-471600D01*
X-1065400Y-471500D01*
X-1069000Y-469300D01*
X-1069600Y-466400D01*
X-1069700Y-463700D01*
X-1068600Y-461200D01*
X-1066700Y-459200D01*
X-1063900Y-457600D01*
X-1061100Y-457000D01*
X-1059600D01*
X-1060200Y-457500D01*
X-1063300Y-458000D01*
X-1065300Y-459500D01*
X-1066900Y-460600D01*
X-1067900Y-462100D01*
X-1068800Y-464300D01*
X-1068700Y-466900D01*
X-1068200Y-469100D01*
X-1066900Y-470200D01*
X-1064300Y-470900D01*
X-1065700Y-469300D01*
X-1065800Y-465900D01*
X-1065300Y-462900D01*
X-1061200Y-458200D01*
X-1063600Y-458900D01*
X-1066400Y-461300D01*
X-1067800Y-464200D01*
Y-467200D01*
X-1067400Y-469300D01*
X-1066300Y-469700D01*
X-1067100Y-466400D01*
X-1066600Y-463400D01*
X-1064700Y-460000D01*
X-1062600Y-458800D01*
X-1065300Y-461700D01*
X-1066700Y-467400D01*
G01X-1060840Y-455100D02*
X-1057160D01*
X-1055260Y-455480D01*
X-1054740Y-455640D01*
X-1053380Y-456420D01*
X-1052660Y-456800D01*
X-1052020Y-457420D01*
X-1051820Y-458020D01*
X-1051200Y-458660D01*
X-1051000Y-459060D01*
X-1050840Y-459200D01*
X-1050700Y-459780D01*
Y-460140D01*
X-1050400Y-460460D01*
X-1050280Y-460680D01*
X-1050100Y-461740D01*
Y-464240D01*
X-1050280Y-465160D01*
X-1050480Y-465980D01*
X-1050680Y-467120D01*
X-1051220Y-468180D01*
X-1051840Y-469020D01*
X-1052040Y-469600D01*
X-1052740Y-470500D01*
X-1054480Y-472240D01*
X-1055000Y-472580D01*
X-1055420Y-472780D01*
X-1056220Y-473380D01*
X-1056920Y-473740D01*
X-1059380Y-474500D01*
X-1065600D01*
X-1067860Y-473740D01*
X-1068160Y-473600D01*
X-1069500Y-472460D01*
X-1069820Y-472120D01*
X-1070380Y-471200D01*
X-1071140Y-469860D01*
X-1071300Y-469400D01*
Y-464580D01*
X-1071120Y-463880D01*
X-1070740Y-462900D01*
X-1070540Y-462320D01*
X-1069980Y-461000D01*
X-1068840Y-459500D01*
X-1066900Y-457560D01*
X-1066180Y-457020D01*
X-1065400Y-456620D01*
X-1064440Y-456040D01*
X-1063500Y-455660D01*
X-1062940Y-455480D01*
X-1060840Y-455100D01*
G01X-1057800Y-458580D02*
X-1057000Y-459120D01*
X-1056760Y-459840D01*
X-1056340Y-460460D01*
X-1056100Y-461640D01*
Y-463760D01*
X-1056320Y-464860D01*
X-1056720Y-466060D01*
X-1056940Y-466920D01*
X-1057200Y-467460D01*
X-1057640Y-467880D01*
X-1058040Y-468480D01*
X-1059960Y-470420D01*
X-1061020Y-470840D01*
X-1061420Y-471100D01*
X-1062720D01*
X-1063340Y-470840D01*
X-1063860Y-470600D01*
X-1064360Y-470080D01*
X-1064820Y-469400D01*
X-1065100Y-468840D01*
Y-464920D01*
X-1064880Y-464120D01*
X-1064420Y-462780D01*
X-1064160Y-462520D01*
X-1063620Y-461700D01*
X-1063200Y-460840D01*
X-1062500Y-460140D01*
X-1062120Y-459860D01*
X-1061720Y-459360D01*
X-1060600Y-458580D01*
X-1060040Y-458300D01*
X-1058360D01*
X-1057800Y-458580D01*
G01X-1040300Y-459100D02*
X-1041400Y-464800D01*
G01X-1044800Y-458200D02*
X-1041400D01*
X-1044300Y-472700D01*
X-1047400Y-472300D01*
X-1044100Y-458800D01*
X-1042400Y-459100D01*
X-1045100Y-471900D01*
X-1046500D01*
X-1043400Y-459700D01*
X-1045600Y-471500D01*
G01X-1036600Y-449900D02*
X-1036800Y-451300D01*
X-1038600Y-452400D01*
X-1039800Y-456100D01*
X-1033700Y-456500D01*
X-1032300Y-452100D01*
X-1028400Y-452000D01*
X-1028900Y-455400D01*
X-1027200Y-456600D01*
X-1025900Y-456800D01*
X-1026200Y-458200D01*
X-1030000Y-458400D01*
X-1031800Y-468900D01*
X-1030400Y-471700D01*
X-1029400D01*
X-1029600Y-473300D01*
X-1033100Y-473400D01*
X-1036100Y-472800D01*
X-1036200Y-470500D01*
X-1035900Y-467100D01*
X-1034400Y-461400D01*
X-1033800Y-458800D01*
X-1033500Y-458400D01*
X-1035000Y-458200D01*
X-1039600D01*
X-1040800Y-458300D01*
X-1043600Y-473200D01*
X-1048000Y-473000D01*
X-1045100Y-459400D01*
X-1044900Y-458400D01*
X-1048700D01*
X-1048100Y-456600D01*
X-1044900Y-456400D01*
X-1045200Y-457700D01*
X-1047600Y-457500D01*
X-1026500D01*
G01X-1049580Y-459100D02*
X-1048740Y-455700D01*
X-1044900D01*
Y-454780D01*
X-1044720Y-454060D01*
X-1044340Y-452920D01*
X-1043940Y-452120D01*
X-1043740Y-451520D01*
X-1043600Y-451260D01*
X-1042340Y-450000D01*
X-1042080Y-449860D01*
X-1040580Y-449480D01*
X-1039440Y-449300D01*
X-1036140D01*
X-1035440Y-449400D01*
X-1035480Y-449540D01*
X-1035680Y-450360D01*
X-1035880Y-451280D01*
X-1036000Y-451900D01*
X-1036740D01*
X-1037060Y-452200D01*
X-1037860Y-452600D01*
X-1038220Y-452980D01*
X-1038480Y-453740D01*
X-1038960Y-455700D01*
X-1034020D01*
X-1033720Y-455080D01*
X-1033500Y-453400D01*
X-1032940Y-451100D01*
X-1027260D01*
X-1027280Y-451180D01*
X-1027480Y-452780D01*
X-1027860Y-454280D01*
X-1028100Y-454760D01*
Y-455700D01*
X-1024800D01*
X-1024880Y-455940D01*
X-1025080Y-456940D01*
X-1025280Y-457540D01*
X-1025480Y-458560D01*
X-1025620Y-459100D01*
X-1029100D01*
Y-460000D01*
X-1029280Y-460540D01*
X-1029480Y-461540D01*
X-1029680Y-462140D01*
X-1029880Y-462960D01*
X-1030100Y-464000D01*
X-1030280Y-465560D01*
X-1030480Y-466140D01*
X-1030680Y-467140D01*
X-1030880Y-467740D01*
X-1031040Y-468400D01*
X-1031300Y-468660D01*
Y-469800D01*
X-1030300Y-470560D01*
X-1029940Y-470900D01*
X-1028220D01*
X-1028680Y-472780D01*
X-1028880Y-474120D01*
Y-474140D01*
X-1030720Y-474300D01*
X-1032860D01*
X-1034380Y-474120D01*
X-1035860Y-473740D01*
X-1036640Y-473280D01*
X-1036960Y-472660D01*
X-1037100Y-472280D01*
Y-470160D01*
X-1036920Y-469260D01*
X-1036700Y-468640D01*
X-1036500Y-466840D01*
X-1036320Y-466260D01*
X-1036120Y-465260D01*
X-1035920Y-464660D01*
X-1035720Y-463660D01*
X-1035520Y-463060D01*
X-1035320Y-462060D01*
X-1035120Y-461440D01*
X-1034820Y-459100D01*
X-1039900D01*
Y-460220D01*
X-1040280Y-461780D01*
X-1040480Y-463380D01*
X-1041280Y-466540D01*
X-1041480Y-467140D01*
X-1041700Y-468200D01*
X-1041880Y-469760D01*
X-1042080Y-470340D01*
X-1042280Y-471360D01*
X-1042480Y-472140D01*
X-1042680Y-472740D01*
X-1042880Y-473740D01*
X-1042940Y-473900D01*
X-1049140D01*
X-1048300Y-470620D01*
X-1048100Y-469020D01*
X-1047920Y-468260D01*
X-1047720Y-467660D01*
X-1047520Y-466660D01*
X-1047320Y-466060D01*
X-1047120Y-465060D01*
X-1046920Y-464460D01*
X-1046700Y-463400D01*
X-1046500Y-462020D01*
X-1046140Y-460500D01*
X-1045900Y-460040D01*
Y-459100D01*
X-1049580D01*
G01X-1038400Y-451100D02*
X-1040600Y-455800D01*
X-1043300D01*
X-1041400Y-451300D01*
X-1038900Y-451000D01*
X-1041200Y-455000D01*
X-1042000Y-455100D01*
X-1040500Y-452000D01*
G01X-1037500Y-449800D02*
X-1037800Y-451000D01*
X-1038500Y-450100D01*
X-1042000Y-450700D01*
X-1043100Y-452300D01*
X-1044100Y-455100D01*
X-1044200Y-456600D01*
X-1036600Y-456800D01*
G01X-1031100Y-472500D02*
X-1031400Y-470900D01*
X-1031900Y-472200D01*
X-1035200D01*
Y-467600D01*
X-1032000Y-453700D01*
X-1030500Y-453800D01*
X-1030000Y-456700D01*
X-1033400Y-471900D01*
X-1034300Y-471600D01*
X-1034200Y-467100D01*
X-1031400Y-454500D01*
X-1030700Y-456500D01*
X-1033700Y-470600D01*
X-1032700Y-461100D01*
G01X-1032000Y-452900D02*
X-1029300D01*
X-1028000Y-457000D01*
X-1029500Y-453600D01*
X-1029100Y-457300D01*
X-1032800Y-472800D01*
X-1030200Y-472600D01*
G54D12*
G01X-1183150Y-540000D02*
Y-552500D01*
G01X-1186485Y-540000D02*
X-1179815D01*
G01X-1171350Y-552500D02*
X-1172510Y-552292D01*
X-1173525Y-551459D01*
X-1174395Y-550208D01*
X-1174975Y-548750D01*
X-1175265Y-547083D01*
Y-545417D01*
X-1174975Y-543750D01*
X-1174395Y-542292D01*
X-1173525Y-541042D01*
X-1172510Y-540208D01*
X-1171350Y-540000D01*
X-1170190Y-540208D01*
X-1169175Y-541042D01*
X-1168305Y-542292D01*
X-1167725Y-543750D01*
X-1167435Y-545417D01*
Y-547083D01*
X-1167725Y-548750D01*
X-1168305Y-550208D01*
X-1169175Y-551459D01*
X-1170190Y-552292D01*
X-1171350Y-552500D01*
G01X-1162450D02*
Y-540000D01*
X-1158970D01*
X-1157810Y-540625D01*
X-1156940Y-542083D01*
X-1156650Y-543750D01*
X-1156940Y-545417D01*
X-1157665Y-546667D01*
X-1158970Y-547292D01*
X-1162450D01*
G01X-1138995Y-550834D02*
X-1137835Y-551875D01*
X-1136530Y-552500D01*
X-1135370D01*
X-1134210Y-551875D01*
X-1133340Y-550834D01*
X-1132905Y-549375D01*
X-1133195Y-547917D01*
X-1133920Y-546667D01*
X-1135225Y-545833D01*
X-1136965Y-545417D01*
X-1137980Y-544584D01*
X-1138415Y-543125D01*
X-1138125Y-541667D01*
X-1137400Y-540625D01*
X-1136385Y-540000D01*
X-1135370D01*
X-1134355Y-540417D01*
X-1133485Y-541458D01*
G01X-1125890Y-540000D02*
X-1122410D01*
G01X-1124150D02*
Y-552500D01*
G01X-1125890D02*
X-1122410D01*
G01X-1115540D02*
Y-540000D01*
X-1112640D01*
X-1111480Y-540625D01*
X-1110610Y-541458D01*
X-1109885Y-542708D01*
X-1109305Y-544167D01*
X-1109160Y-546250D01*
X-1109305Y-548333D01*
X-1109885Y-549792D01*
X-1110610Y-551042D01*
X-1111480Y-551875D01*
X-1112640Y-552500D01*
X-1115540D01*
G01X-1097650D02*
X-1103450D01*
Y-540000D01*
X-1097650D01*
G01X-1099970Y-546042D02*
X-1103450D01*
G01X-1079995Y-550834D02*
X-1078835Y-551875D01*
X-1077530Y-552500D01*
X-1076370D01*
X-1075210Y-551875D01*
X-1074340Y-550834D01*
X-1073905Y-549375D01*
X-1074195Y-547917D01*
X-1074920Y-546667D01*
X-1076225Y-545833D01*
X-1077965Y-545417D01*
X-1078980Y-544584D01*
X-1079415Y-543125D01*
X-1079125Y-541667D01*
X-1078400Y-540625D01*
X-1077385Y-540000D01*
X-1076370D01*
X-1075355Y-540417D01*
X-1074485Y-541458D01*
G01X-1066890Y-540000D02*
X-1063410D01*
G01X-1065150D02*
Y-552500D01*
G01X-1066890D02*
X-1063410D01*
G01X-1056250Y-540000D02*
Y-552500D01*
X-1050450D01*
G01X-1044740D02*
Y-540000D01*
G01X-1039230D02*
X-1044740Y-547709D01*
G01X-1038360Y-552500D02*
X-1042275Y-544167D01*
G01X-1032795Y-550834D02*
X-1031635Y-551875D01*
X-1030330Y-552500D01*
X-1029170D01*
X-1028010Y-551875D01*
X-1027140Y-550834D01*
X-1026705Y-549375D01*
X-1026995Y-547917D01*
X-1027720Y-546667D01*
X-1029025Y-545833D01*
X-1030765Y-545417D01*
X-1031780Y-544584D01*
X-1032215Y-543125D01*
X-1031925Y-541667D01*
X-1031200Y-540625D01*
X-1030185Y-540000D01*
X-1029170D01*
X-1028155Y-540417D01*
X-1027285Y-541458D01*
G01X-1014760Y-541042D02*
X-1015630Y-540417D01*
X-1016645Y-540000D01*
X-1017805D01*
X-1019110Y-540625D01*
X-1020125Y-541667D01*
X-1020850Y-542917D01*
X-1021430Y-545000D01*
X-1021575Y-546875D01*
X-1021285Y-548750D01*
X-1020850Y-550000D01*
X-1019980Y-551250D01*
X-1018965Y-552083D01*
X-1017950Y-552500D01*
X-1016935D01*
X-1015920Y-552083D01*
X-1015050Y-551459D01*
X-1014325Y-550625D01*
G01X-1009050Y-552500D02*
Y-540000D01*
X-1005425D01*
X-1004265Y-540625D01*
X-1003540Y-541458D01*
X-1003250Y-543125D01*
X-1003540Y-544792D01*
X-1004410Y-545833D01*
X-1005425Y-546458D01*
X-1009050D01*
G01X-1005425D02*
X-1003250Y-552500D01*
G01X-991450D02*
X-997250D01*
Y-540000D01*
X-991450D01*
G01X-993770Y-546042D02*
X-997250D01*
G01X-979650Y-552500D02*
X-985450D01*
Y-540000D01*
X-979650D01*
G01X-981970Y-546042D02*
X-985450D01*
G01X-974085Y-552500D02*
Y-540000D01*
X-967415Y-552500D01*
Y-540000D01*
G54D13*
G01X-1657611Y-122050D02*
X-1658711Y-120950D01*
G01X-1658911Y-121500D02*
X-1657411D01*
G01X-1657611Y-120950D02*
X-1658711Y-122050D01*
G01X-1658161Y-122250D02*
Y-120750D01*
G01X-1626550Y-12050D02*
X-1625450Y-10950D01*
G01X-1626000Y-10750D02*
Y-12250D01*
G01X-1625450Y-12050D02*
X-1626550Y-10950D01*
G01X-1626750Y-11500D02*
X-1625250D01*
G01X-1539763Y-184144D02*
X-1538663Y-183044D01*
G01X-1539213Y-182844D02*
Y-184344D01*
G01X-1538663Y-184144D02*
X-1539763Y-183044D01*
G01X-1539963Y-183595D02*
X-1538463D01*
G01X-1501743Y-168840D02*
X-1500643Y-169940D01*
G01X-1500443Y-169390D02*
X-1501943D01*
G01X-1501743Y-169940D02*
X-1500643Y-168840D01*
G01X-1501193Y-168640D02*
Y-170140D01*
G01X-1328450Y-103050D02*
X-1329550Y-101950D01*
G01X-1329750Y-102500D02*
X-1328250D01*
G01X-1328450Y-101950D02*
X-1329550Y-103050D01*
G01X-1329000Y-103250D02*
Y-101750D01*
G01X-1320050Y-6550D02*
X-1321150Y-5450D01*
G01X-1321350Y-6000D02*
X-1319850D01*
G01X-1320050Y-5450D02*
X-1321150Y-6550D01*
G01X-1320600Y-6750D02*
Y-5250D01*
G01X-1289250Y-7450D02*
X-1290350Y-6350D01*
G01X-1290550Y-6900D02*
X-1289050D01*
G01X-1289250Y-6350D02*
X-1290350Y-7450D01*
G01X-1289800Y-7650D02*
Y-6150D01*
G01X-1213860Y-157890D02*
X-1212760Y-156790D01*
G01X-1213310Y-156590D02*
Y-158090D01*
G01X-1212760Y-157890D02*
X-1213860Y-156790D01*
G01X-1214060Y-157340D02*
X-1212560D01*
G01X-1185925Y-592500D02*
X-1178575Y-577500D01*
G01X-1185925D02*
X-1178575Y-592500D01*
G01X-1168050D02*
X-1166825Y-592250D01*
X-1165425Y-591500D01*
X-1164550Y-590250D01*
X-1164200Y-588500D01*
X-1164550Y-586750D01*
X-1165600Y-585250D01*
X-1167175Y-584500D01*
X-1168925D01*
X-1169975Y-584000D01*
X-1170850Y-582750D01*
X-1171200Y-581000D01*
X-1170675Y-579250D01*
X-1169450Y-578000D01*
X-1168050Y-577500D01*
X-1166650Y-578000D01*
X-1165425Y-579250D01*
X-1164900Y-581000D01*
X-1165250Y-582750D01*
X-1166125Y-584000D01*
X-1167175Y-584500D01*
X-1168925D01*
X-1170500Y-585250D01*
X-1171550Y-586750D01*
X-1171900Y-588500D01*
X-1171550Y-590250D01*
X-1170675Y-591500D01*
X-1169275Y-592250D01*
X-1168050Y-592500D01*
G01X-1153850D02*
X-1152625Y-592250D01*
X-1151225Y-591500D01*
X-1150350Y-590250D01*
X-1150000Y-588500D01*
X-1150350Y-586750D01*
X-1151400Y-585250D01*
X-1152975Y-584500D01*
X-1154725D01*
X-1155775Y-584000D01*
X-1156650Y-582750D01*
X-1157000Y-581000D01*
X-1156475Y-579250D01*
X-1155250Y-578000D01*
X-1153850Y-577500D01*
X-1152450Y-578000D01*
X-1151225Y-579250D01*
X-1150700Y-581000D01*
X-1151050Y-582750D01*
X-1151925Y-584000D01*
X-1152975Y-584500D01*
X-1154725D01*
X-1156300Y-585250D01*
X-1157350Y-586750D01*
X-1157700Y-588500D01*
X-1157350Y-590250D01*
X-1156475Y-591500D01*
X-1155075Y-592250D01*
X-1153850Y-592500D01*
G01X-1140000D02*
X-1139650Y-589250D01*
X-1139125Y-586500D01*
X-1138425Y-584000D01*
X-1137550Y-581250D01*
X-1136150Y-577500D01*
X-1143150D01*
G01X-1129300Y-590250D02*
X-1128250Y-591500D01*
X-1127025Y-592250D01*
X-1125450Y-592500D01*
X-1123875Y-592000D01*
X-1122650Y-591000D01*
X-1121775Y-589250D01*
X-1121600Y-587250D01*
X-1121950Y-585250D01*
X-1122825Y-584000D01*
X-1124050Y-583000D01*
X-1125275Y-582750D01*
X-1126500Y-583000D01*
X-1128075Y-584000D01*
X-1127550Y-577500D01*
X-1122825D01*
G01X-1111600Y-592500D02*
X-1111250Y-589250D01*
X-1110725Y-586500D01*
X-1110025Y-584000D01*
X-1109150Y-581250D01*
X-1107750Y-577500D01*
X-1114750D01*
G01X-1097050Y-592500D02*
Y-577500D01*
X-1099150Y-580500D01*
G01Y-592500D02*
X-1094950D01*
G01X-1085125Y-587500D02*
X-1080575D01*
G01X-1068650Y-577500D02*
X-1070050Y-578000D01*
X-1071100Y-579250D01*
X-1071800Y-580750D01*
X-1072325Y-582750D01*
X-1072500Y-585000D01*
X-1072325Y-587250D01*
X-1071800Y-589250D01*
X-1071100Y-590750D01*
X-1070050Y-592000D01*
X-1068650Y-592500D01*
X-1067250Y-592000D01*
X-1066200Y-590750D01*
X-1065500Y-589250D01*
X-1064975Y-587250D01*
X-1064800Y-585000D01*
X-1064975Y-582750D01*
X-1065500Y-580750D01*
X-1066200Y-579250D01*
X-1067250Y-578000D01*
X-1068650Y-577500D01*
G01X-1054450D02*
X-1055850Y-578000D01*
X-1056900Y-579250D01*
X-1057600Y-580750D01*
X-1058125Y-582750D01*
X-1058300Y-585000D01*
X-1058125Y-587250D01*
X-1057600Y-589250D01*
X-1056900Y-590750D01*
X-1055850Y-592000D01*
X-1054450Y-592500D01*
X-1053050Y-592000D01*
X-1052000Y-590750D01*
X-1051300Y-589250D01*
X-1050775Y-587250D01*
X-1050600Y-585000D01*
X-1050775Y-582750D01*
X-1051300Y-580750D01*
X-1052000Y-579250D01*
X-1053050Y-578000D01*
X-1054450Y-577500D01*
G01X-1044100Y-590250D02*
X-1043050Y-591500D01*
X-1041825Y-592250D01*
X-1040250Y-592500D01*
X-1038675Y-592000D01*
X-1037450Y-591000D01*
X-1036575Y-589250D01*
X-1036400Y-587250D01*
X-1036750Y-585250D01*
X-1037625Y-584000D01*
X-1038850Y-583000D01*
X-1040075Y-582750D01*
X-1041300Y-583000D01*
X-1042875Y-584000D01*
X-1042350Y-577500D01*
X-1037625D01*
G01X-1150050Y-184050D02*
X-1148950Y-182950D01*
G01X-1149500Y-182750D02*
Y-184250D01*
G01X-1148950Y-184050D02*
X-1150050Y-182950D01*
G01X-1150250Y-183500D02*
X-1148750D01*
G01X-1095400Y-104340D02*
X-1094300Y-103240D01*
G01X-1094850Y-103040D02*
Y-104540D01*
G01X-1094300Y-104340D02*
X-1095400Y-103240D01*
G01X-1095600Y-103790D02*
X-1094100D01*
G01X-969050Y-184050D02*
X-967950Y-182950D01*
G01X-968500Y-182750D02*
Y-184250D01*
G01X-967950Y-184050D02*
X-969050Y-182950D01*
G01X-969250Y-183500D02*
X-967750D01*
G01X-935050Y-55050D02*
X-933950Y-53950D01*
G01X-934500Y-53750D02*
Y-55250D01*
G01X-933950Y-55050D02*
X-935050Y-53950D01*
G01X-935250Y-54500D02*
X-933750D01*
G01X-911875Y-592500D02*
X-907500Y-577500D01*
X-903125Y-592500D01*
G01X-904700Y-587250D02*
X-910300D01*
G01X-802340Y-162400D02*
X-803440Y-161300D01*
G01X-803640Y-161850D02*
X-802140D01*
G01X-802340Y-161300D02*
X-803440Y-162400D01*
G01X-802890Y-162600D02*
Y-161100D01*
G01X-768050Y-83450D02*
X-766950Y-84550D01*
G01X-766750Y-84000D02*
X-768250D01*
G01X-768050Y-84550D02*
X-766950Y-83450D01*
G01X-767500Y-83250D02*
Y-84750D01*
G01X-669684Y-184144D02*
X-668584Y-183044D01*
G01X-669134Y-182844D02*
Y-184344D01*
G01X-668584Y-184144D02*
X-669684Y-183044D01*
G01X-669884Y-183595D02*
X-668384D01*
G01X-631664Y-168840D02*
X-630564Y-169940D01*
G01X-630364Y-169390D02*
X-631864D01*
G01X-631664Y-169940D02*
X-630564Y-168840D01*
G01X-631114Y-168640D02*
Y-170140D01*
G01X-467470Y-128345D02*
X-468570Y-127245D01*
G01X-468770Y-127795D02*
X-467270D01*
G01X-467470Y-127245D02*
X-468570Y-128345D01*
G01X-468020Y-128545D02*
Y-127045D01*
G01X-449971Y-6550D02*
X-451071Y-5450D01*
G01X-451271Y-6000D02*
X-449771D01*
G01X-449971Y-5450D02*
X-451071Y-6550D01*
G01X-450521Y-6750D02*
Y-5250D01*
G01X-419171Y-7450D02*
X-420271Y-6350D01*
G01X-420471Y-6900D02*
X-418971D01*
G01X-419171Y-6350D02*
X-420271Y-7450D01*
G01X-419721Y-7650D02*
Y-6150D01*
G01X-343730Y-156870D02*
X-342630Y-155770D01*
G01X-343180Y-155570D02*
Y-157070D01*
G01X-342630Y-156870D02*
X-343730Y-155770D01*
G01X-343930Y-156320D02*
X-342430D01*
G01X-286550Y-183550D02*
X-285450Y-182450D01*
G01X-286000Y-182250D02*
Y-183750D01*
G01X-285450Y-183550D02*
X-286550Y-182450D01*
G01X-286750Y-183000D02*
X-285250D01*
G01X-225550Y-108948D02*
X-224450Y-107848D01*
G01X-225000Y-107648D02*
Y-109148D01*
G01X-224450Y-108948D02*
X-225550Y-107848D01*
G01X-225750Y-108398D02*
X-224250D01*
G01X-99684Y-184538D02*
X-98584Y-183438D01*
G01X-99134Y-183238D02*
Y-184738D01*
G01X-98584Y-184538D02*
X-99684Y-183438D01*
G01X-99884Y-183988D02*
X-98384D01*
G01X-63450Y-55950D02*
X-64550Y-57050D01*
G01X-64000Y-57250D02*
Y-55750D01*
G01X-64550Y-55950D02*
X-63450Y-57050D01*
G01X-63250Y-56500D02*
X-64750D01*
G54D14*
G01X-1658352Y-100650D02*
Y-97650D01*
X-1659647Y-99800D01*
X-1657897D01*
G01X-1653875Y-14381D02*
X-1653625Y-14101D01*
X-1653475Y-13786D01*
Y-13506D01*
X-1653625Y-13226D01*
X-1653875Y-13016D01*
X-1654225Y-12911D01*
X-1654575Y-12981D01*
X-1654875Y-13156D01*
X-1655075Y-13471D01*
X-1655175Y-13891D01*
X-1655375Y-14136D01*
X-1655725Y-14241D01*
X-1656075Y-14171D01*
X-1656325Y-13996D01*
X-1656475Y-13751D01*
Y-13506D01*
X-1656375Y-13261D01*
X-1656125Y-13051D01*
G01X-1654725Y-11511D02*
X-1655075Y-11266D01*
X-1655275Y-11056D01*
X-1655375Y-10776D01*
X-1655275Y-10531D01*
X-1655075Y-10356D01*
X-1654775Y-10216D01*
X-1654425Y-10181D01*
X-1654125Y-10216D01*
X-1653825Y-10356D01*
X-1653575Y-10566D01*
X-1653475Y-10811D01*
X-1653575Y-11091D01*
X-1653875Y-11336D01*
X-1654325Y-11476D01*
X-1654825Y-11511D01*
X-1655475Y-11441D01*
X-1655825Y-11336D01*
X-1656175Y-11161D01*
X-1656425Y-10916D01*
X-1656475Y-10671D01*
X-1656375Y-10426D01*
X-1656125Y-10251D01*
G01X-1649410Y-150700D02*
Y-147700D01*
X-1648500Y-150200D01*
X-1647590Y-147700D01*
Y-150700D01*
G01X-1646435D02*
Y-147700D01*
G01X-1644965D02*
Y-150700D01*
G01Y-149200D02*
X-1646435D01*
G01X-1642900Y-150700D02*
Y-147700D01*
X-1643320Y-148300D01*
G01Y-150700D02*
X-1642480D01*
G01X-1628278Y-179958D02*
X-1627403Y-176958D01*
X-1626527Y-179958D01*
G01X-1626843Y-178908D02*
X-1627963D01*
G01X-1624603Y-179958D02*
Y-176958D01*
X-1625023Y-177558D01*
G01Y-179958D02*
X-1624183D01*
G01X-1621803Y-176958D02*
X-1622083Y-177058D01*
X-1622293Y-177308D01*
X-1622433Y-177608D01*
X-1622538Y-178008D01*
X-1622573Y-178458D01*
X-1622538Y-178908D01*
X-1622433Y-179308D01*
X-1622293Y-179608D01*
X-1622083Y-179858D01*
X-1621803Y-179958D01*
X-1621523Y-179858D01*
X-1621313Y-179608D01*
X-1621172Y-179308D01*
X-1621068Y-178908D01*
X-1621033Y-178458D01*
X-1621068Y-178008D01*
X-1621172Y-177608D01*
X-1621313Y-177308D01*
X-1621523Y-177058D01*
X-1621803Y-176958D01*
G01X-1626703Y-157911D02*
X-1628103D01*
Y-154911D01*
X-1626703D01*
G01X-1627263Y-156361D02*
X-1628103D01*
G01X-1624603Y-157911D02*
Y-154911D01*
X-1625023Y-155511D01*
G01Y-157911D02*
X-1624183D01*
G01X-1621803Y-154911D02*
X-1622083Y-155011D01*
X-1622293Y-155261D01*
X-1622433Y-155561D01*
X-1622538Y-155961D01*
X-1622573Y-156411D01*
X-1622538Y-156861D01*
X-1622433Y-157261D01*
X-1622293Y-157561D01*
X-1622083Y-157811D01*
X-1621803Y-157911D01*
X-1621523Y-157811D01*
X-1621313Y-157561D01*
X-1621172Y-157261D01*
X-1621068Y-156861D01*
X-1621033Y-156411D01*
X-1621068Y-155961D01*
X-1621172Y-155561D01*
X-1621313Y-155261D01*
X-1621523Y-155011D01*
X-1621803Y-154911D01*
G01X-1628103Y-129752D02*
X-1627927Y-130052D01*
X-1627718Y-130252D01*
X-1627473Y-130352D01*
X-1627193Y-130252D01*
X-1626983Y-130052D01*
X-1626772Y-129752D01*
X-1626703Y-129352D01*
Y-127352D01*
G01X-1624603Y-130352D02*
Y-127352D01*
X-1625023Y-127952D01*
G01Y-130352D02*
X-1624183D01*
G01X-1621803Y-127352D02*
X-1622083Y-127452D01*
X-1622293Y-127702D01*
X-1622433Y-128002D01*
X-1622538Y-128402D01*
X-1622573Y-128852D01*
X-1622538Y-129302D01*
X-1622433Y-129702D01*
X-1622293Y-130002D01*
X-1622083Y-130252D01*
X-1621803Y-130352D01*
X-1621523Y-130252D01*
X-1621313Y-130002D01*
X-1621172Y-129702D01*
X-1621068Y-129302D01*
X-1621033Y-128852D01*
X-1621068Y-128402D01*
X-1621172Y-128002D01*
X-1621313Y-127702D01*
X-1621523Y-127452D01*
X-1621803Y-127352D01*
G01X-1634170Y-107500D02*
Y-109650D01*
X-1634030Y-110100D01*
X-1633750Y-110400D01*
X-1633400Y-110500D01*
X-1633050Y-110400D01*
X-1632770Y-110100D01*
X-1632630Y-109650D01*
Y-107500D01*
G01X-1631265Y-108000D02*
X-1631055Y-107700D01*
X-1630810Y-107550D01*
X-1630530Y-107500D01*
X-1630180Y-107600D01*
X-1629935Y-107850D01*
X-1629865Y-108150D01*
X-1629900Y-108450D01*
X-1630040Y-108700D01*
X-1630740Y-109200D01*
X-1631055Y-109550D01*
X-1631265Y-110050D01*
X-1631335Y-110500D01*
X-1629865D01*
G01X-1628500Y-95500D02*
Y-92500D01*
X-1627660D01*
X-1627380Y-92650D01*
X-1627170Y-93000D01*
X-1627100Y-93400D01*
X-1627170Y-93800D01*
X-1627345Y-94100D01*
X-1627660Y-94250D01*
X-1628500D01*
G01X-1625000Y-95500D02*
Y-92500D01*
X-1625420Y-93100D01*
G01Y-95500D02*
X-1624580D01*
G01X-1622200Y-92500D02*
X-1622480Y-92600D01*
X-1622690Y-92850D01*
X-1622830Y-93150D01*
X-1622935Y-93550D01*
X-1622970Y-94000D01*
X-1622935Y-94450D01*
X-1622830Y-94850D01*
X-1622690Y-95150D01*
X-1622480Y-95400D01*
X-1622200Y-95500D01*
X-1621920Y-95400D01*
X-1621710Y-95150D01*
X-1621570Y-94850D01*
X-1621465Y-94450D01*
X-1621430Y-94000D01*
X-1621465Y-93550D01*
X-1621570Y-93150D01*
X-1621710Y-92850D01*
X-1621920Y-92600D01*
X-1622200Y-92500D01*
G01X-1628875Y-14381D02*
X-1628625Y-14101D01*
X-1628475Y-13786D01*
Y-13506D01*
X-1628625Y-13226D01*
X-1628875Y-13016D01*
X-1629225Y-12911D01*
X-1629575Y-12981D01*
X-1629875Y-13156D01*
X-1630075Y-13471D01*
X-1630175Y-13891D01*
X-1630375Y-14136D01*
X-1630725Y-14241D01*
X-1631075Y-14171D01*
X-1631325Y-13996D01*
X-1631475Y-13751D01*
Y-13506D01*
X-1631375Y-13261D01*
X-1631125Y-13051D01*
G01X-1628475Y-10846D02*
X-1631475D01*
X-1630875Y-11266D01*
G01X-1628475D02*
Y-10427D01*
G01X-1611600Y-17500D02*
Y-14500D01*
X-1610760D01*
X-1610480Y-14650D01*
X-1610270Y-15000D01*
X-1610200Y-15400D01*
X-1610270Y-15800D01*
X-1610445Y-16100D01*
X-1610760Y-16250D01*
X-1611600D01*
G01X-1608100Y-17500D02*
Y-14500D01*
X-1608520Y-15100D01*
G01Y-17500D02*
X-1607680D01*
G01X-1606070Y-16900D02*
X-1605860Y-17250D01*
X-1605580Y-17450D01*
X-1605265Y-17500D01*
X-1604985Y-17450D01*
X-1604705Y-17200D01*
X-1604530Y-16900D01*
X-1604495Y-16600D01*
X-1604565Y-16250D01*
X-1604810Y-16000D01*
X-1605055Y-15900D01*
X-1605370D01*
G01X-1605055D02*
X-1604845Y-15750D01*
X-1604670Y-15500D01*
X-1604600Y-15200D01*
X-1604670Y-14900D01*
X-1604845Y-14650D01*
X-1605160Y-14500D01*
X-1605475Y-14550D01*
X-1605790Y-14750D01*
G01X-1602955Y-16500D02*
X-1602045D01*
G01X-1600400Y-17500D02*
Y-14500D01*
X-1599560D01*
X-1599280Y-14650D01*
X-1599070Y-15000D01*
X-1599000Y-15400D01*
X-1599070Y-15800D01*
X-1599245Y-16100D01*
X-1599560Y-16250D01*
X-1600400D01*
G01X-1596900Y-17500D02*
Y-14500D01*
X-1597320Y-15100D01*
G01Y-17500D02*
X-1596480D01*
G01X-1594765Y-16250D02*
X-1594520Y-15900D01*
X-1594310Y-15700D01*
X-1594030Y-15600D01*
X-1593785Y-15700D01*
X-1593610Y-15900D01*
X-1593470Y-16200D01*
X-1593435Y-16550D01*
X-1593470Y-16850D01*
X-1593610Y-17150D01*
X-1593820Y-17400D01*
X-1594065Y-17500D01*
X-1594345Y-17400D01*
X-1594590Y-17100D01*
X-1594730Y-16650D01*
X-1594765Y-16150D01*
X-1594695Y-15500D01*
X-1594590Y-15150D01*
X-1594415Y-14800D01*
X-1594170Y-14550D01*
X-1593925Y-14500D01*
X-1593680Y-14600D01*
X-1593505Y-14850D01*
G01X-1582651Y-82148D02*
X-1582476Y-82448D01*
X-1582266Y-82648D01*
X-1582021Y-82748D01*
X-1581741Y-82648D01*
X-1581531Y-82448D01*
X-1581321Y-82148D01*
X-1581251Y-81748D01*
Y-79748D01*
G01X-1579151Y-82748D02*
Y-79748D01*
X-1579571Y-80348D01*
G01Y-82748D02*
X-1578731D01*
G01X-1564200Y-17500D02*
Y-14500D01*
X-1563360D01*
X-1563080Y-14650D01*
X-1562870Y-15000D01*
X-1562800Y-15400D01*
X-1562870Y-15800D01*
X-1563045Y-16100D01*
X-1563360Y-16250D01*
X-1564200D01*
G01X-1561295Y-17150D02*
X-1561050Y-17400D01*
X-1560770Y-17500D01*
X-1560490Y-17400D01*
X-1560245Y-17100D01*
X-1560070Y-16650D01*
X-1560000Y-16200D01*
Y-15650D01*
X-1560070Y-15200D01*
X-1560245Y-14800D01*
X-1560455Y-14600D01*
X-1560700Y-14500D01*
X-1560980Y-14600D01*
X-1561190Y-14800D01*
X-1561330Y-15100D01*
X-1561400Y-15500D01*
X-1561330Y-15850D01*
X-1561155Y-16200D01*
X-1560945Y-16400D01*
X-1560700Y-16450D01*
X-1560420Y-16350D01*
X-1560210Y-16100D01*
X-1560000Y-15650D01*
G01X-1558355Y-16500D02*
X-1557445D01*
G01X-1555800Y-17500D02*
Y-14500D01*
X-1554960D01*
X-1554680Y-14650D01*
X-1554470Y-15000D01*
X-1554400Y-15400D01*
X-1554470Y-15800D01*
X-1554645Y-16100D01*
X-1554960Y-16250D01*
X-1555800D01*
G01X-1552300Y-17500D02*
Y-14500D01*
X-1552720Y-15100D01*
G01Y-17500D02*
X-1551880D01*
G01X-1550165Y-15000D02*
X-1549955Y-14700D01*
X-1549710Y-14550D01*
X-1549430Y-14500D01*
X-1549080Y-14600D01*
X-1548835Y-14850D01*
X-1548765Y-15150D01*
X-1548800Y-15450D01*
X-1548940Y-15700D01*
X-1549640Y-16200D01*
X-1549955Y-16550D01*
X-1550165Y-17050D01*
X-1550235Y-17500D01*
X-1548765D01*
G01X-1540263Y-179958D02*
X-1539388Y-176958D01*
X-1538513Y-179958D01*
G01X-1538828Y-178908D02*
X-1539948D01*
G01X-1536588Y-179958D02*
Y-176958D01*
X-1537008Y-177558D01*
G01Y-179958D02*
X-1536168D01*
G01X-1540088Y-129752D02*
X-1539913Y-130052D01*
X-1539703Y-130252D01*
X-1539458Y-130352D01*
X-1539178Y-130252D01*
X-1538968Y-130052D01*
X-1538758Y-129752D01*
X-1538688Y-129352D01*
Y-127352D01*
G01X-1536588Y-130352D02*
Y-127352D01*
X-1537008Y-127952D01*
G01Y-130352D02*
X-1536168D01*
G01X-1539388Y-102793D02*
X-1539668Y-102743D01*
X-1539913Y-102543D01*
X-1540123Y-102243D01*
X-1540263Y-101893D01*
X-1540333Y-101493D01*
Y-101093D01*
X-1540263Y-100693D01*
X-1540123Y-100342D01*
X-1539913Y-100043D01*
X-1539668Y-99843D01*
X-1539388Y-99793D01*
X-1539108Y-99843D01*
X-1538863Y-100043D01*
X-1538653Y-100342D01*
X-1538513Y-100693D01*
X-1538443Y-101093D01*
Y-101493D01*
X-1538513Y-101893D01*
X-1538653Y-102243D01*
X-1538863Y-102543D01*
X-1539108Y-102743D01*
X-1539388Y-102793D01*
G01X-1536588D02*
Y-99793D01*
X-1537008Y-100392D01*
G01Y-102793D02*
X-1536168D01*
G01X-1541670Y-23500D02*
Y-25650D01*
X-1541530Y-26100D01*
X-1541250Y-26400D01*
X-1540900Y-26500D01*
X-1540550Y-26400D01*
X-1540270Y-26100D01*
X-1540130Y-25650D01*
Y-23500D01*
G01X-1538100Y-26500D02*
Y-23500D01*
X-1538520Y-24100D01*
G01Y-26500D02*
X-1537680D01*
G01X-1526438Y-136950D02*
Y-133950D01*
X-1525528Y-136450D01*
X-1524618Y-133950D01*
Y-136950D01*
G01X-1523463D02*
Y-133950D01*
G01X-1521993D02*
Y-136950D01*
G01Y-135450D02*
X-1523463D01*
G01X-1520593Y-134450D02*
X-1520383Y-134150D01*
X-1520138Y-134000D01*
X-1519858Y-133950D01*
X-1519508Y-134050D01*
X-1519263Y-134300D01*
X-1519193Y-134600D01*
X-1519228Y-134900D01*
X-1519368Y-135150D01*
X-1520068Y-135650D01*
X-1520383Y-136000D01*
X-1520593Y-136500D01*
X-1520663Y-136950D01*
X-1519193D01*
G01X-1511500Y-126500D02*
X-1514500D01*
Y-125625D01*
X-1514350Y-125345D01*
X-1514150Y-125170D01*
X-1513750Y-125100D01*
X-1513350Y-125170D01*
X-1513100Y-125380D01*
X-1512950Y-125625D01*
Y-126500D01*
G01Y-125625D02*
X-1511500Y-125100D01*
G01Y-123000D02*
X-1511550Y-122755D01*
X-1511700Y-122475D01*
X-1511950Y-122300D01*
X-1512300Y-122230D01*
X-1512650Y-122300D01*
X-1512950Y-122510D01*
X-1513100Y-122825D01*
Y-123175D01*
X-1513200Y-123385D01*
X-1513450Y-123560D01*
X-1513800Y-123630D01*
X-1514150Y-123525D01*
X-1514400Y-123280D01*
X-1514500Y-123000D01*
X-1514400Y-122720D01*
X-1514150Y-122475D01*
X-1513800Y-122370D01*
X-1513450Y-122440D01*
X-1513200Y-122615D01*
X-1513100Y-122825D01*
Y-123175D01*
X-1512950Y-123490D01*
X-1512650Y-123700D01*
X-1512300Y-123770D01*
X-1511950Y-123700D01*
X-1511700Y-123525D01*
X-1511550Y-123245D01*
X-1511500Y-123000D01*
G01X-1511950Y-120970D02*
X-1511700Y-120760D01*
X-1511550Y-120515D01*
X-1511500Y-120200D01*
X-1511600Y-119885D01*
X-1511800Y-119640D01*
X-1512150Y-119465D01*
X-1512550Y-119430D01*
X-1512950Y-119500D01*
X-1513200Y-119675D01*
X-1513400Y-119920D01*
X-1513450Y-120165D01*
X-1513400Y-120410D01*
X-1513200Y-120725D01*
X-1514500Y-120620D01*
Y-119675D01*
G01X-1522560Y-16100D02*
Y-13100D01*
X-1521720D01*
X-1521440Y-13250D01*
X-1521230Y-13600D01*
X-1521160Y-14000D01*
X-1521230Y-14400D01*
X-1521405Y-14700D01*
X-1521720Y-14850D01*
X-1522560D01*
G01X-1519830Y-15650D02*
X-1519620Y-15900D01*
X-1519375Y-16050D01*
X-1519060Y-16100D01*
X-1518745Y-16000D01*
X-1518500Y-15800D01*
X-1518325Y-15450D01*
X-1518290Y-15050D01*
X-1518360Y-14650D01*
X-1518535Y-14400D01*
X-1518780Y-14200D01*
X-1519025Y-14150D01*
X-1519270Y-14200D01*
X-1519585Y-14400D01*
X-1519480Y-13100D01*
X-1518535D01*
G01X-1516715Y-15100D02*
X-1515805D01*
G01X-1514160Y-16100D02*
Y-13100D01*
X-1513320D01*
X-1513040Y-13250D01*
X-1512830Y-13600D01*
X-1512760Y-14000D01*
X-1512830Y-14400D01*
X-1513005Y-14700D01*
X-1513320Y-14850D01*
X-1514160D01*
G01X-1510660Y-16100D02*
X-1510415Y-16050D01*
X-1510135Y-15900D01*
X-1509960Y-15650D01*
X-1509890Y-15300D01*
X-1509960Y-14950D01*
X-1510170Y-14650D01*
X-1510485Y-14500D01*
X-1510835D01*
X-1511045Y-14400D01*
X-1511220Y-14150D01*
X-1511290Y-13800D01*
X-1511185Y-13450D01*
X-1510940Y-13200D01*
X-1510660Y-13100D01*
X-1510380Y-13200D01*
X-1510135Y-13450D01*
X-1510030Y-13800D01*
X-1510100Y-14150D01*
X-1510275Y-14400D01*
X-1510485Y-14500D01*
X-1510835D01*
X-1511150Y-14650D01*
X-1511360Y-14950D01*
X-1511430Y-15300D01*
X-1511360Y-15650D01*
X-1511185Y-15900D01*
X-1510905Y-16050D01*
X-1510660Y-16100D01*
G01X-1506300Y-75500D02*
Y-72500D01*
X-1506720Y-73100D01*
G01Y-75500D02*
X-1505880D01*
G01X-1504270Y-75050D02*
X-1504060Y-75300D01*
X-1503815Y-75450D01*
X-1503500Y-75500D01*
X-1503185Y-75400D01*
X-1502940Y-75200D01*
X-1502765Y-74850D01*
X-1502730Y-74450D01*
X-1502800Y-74050D01*
X-1502975Y-73800D01*
X-1503220Y-73600D01*
X-1503465Y-73550D01*
X-1503710Y-73600D01*
X-1504025Y-73800D01*
X-1503920Y-72500D01*
X-1502975D01*
G01X-1501470Y-74900D02*
X-1501260Y-75250D01*
X-1500980Y-75450D01*
X-1500665Y-75500D01*
X-1500385Y-75450D01*
X-1500105Y-75200D01*
X-1499930Y-74900D01*
X-1499895Y-74600D01*
X-1499965Y-74250D01*
X-1500210Y-74000D01*
X-1500455Y-73900D01*
X-1500770D01*
G01X-1500455D02*
X-1500245Y-73750D01*
X-1500070Y-73500D01*
X-1500000Y-73200D01*
X-1500070Y-72900D01*
X-1500245Y-72650D01*
X-1500560Y-72500D01*
X-1500875Y-72550D01*
X-1501190Y-72750D01*
G01X-1487500Y-16280D02*
Y-13280D01*
X-1486660D01*
X-1486380Y-13430D01*
X-1486170Y-13780D01*
X-1486100Y-14180D01*
X-1486170Y-14580D01*
X-1486345Y-14880D01*
X-1486660Y-15030D01*
X-1487500D01*
G01X-1484000Y-16280D02*
Y-13280D01*
X-1484420Y-13880D01*
G01Y-16280D02*
X-1483580D01*
G01X-1481655Y-15280D02*
X-1480745D01*
G01X-1479100Y-16280D02*
Y-13280D01*
X-1478260D01*
X-1477980Y-13430D01*
X-1477770Y-13780D01*
X-1477700Y-14180D01*
X-1477770Y-14580D01*
X-1477945Y-14880D01*
X-1478260Y-15030D01*
X-1479100D01*
G01X-1475180Y-16280D02*
Y-13280D01*
X-1476475Y-15430D01*
X-1474725D01*
G01X-1474320Y-54730D02*
X-1474145Y-55030D01*
X-1473935Y-55230D01*
X-1473690Y-55330D01*
X-1473410Y-55230D01*
X-1473200Y-55030D01*
X-1472990Y-54730D01*
X-1472920Y-54330D01*
Y-52330D01*
G01X-1471485Y-52830D02*
X-1471275Y-52530D01*
X-1471030Y-52380D01*
X-1470750Y-52330D01*
X-1470400Y-52430D01*
X-1470155Y-52680D01*
X-1470085Y-52980D01*
X-1470120Y-53280D01*
X-1470260Y-53530D01*
X-1470960Y-54030D01*
X-1471275Y-54380D01*
X-1471485Y-54880D01*
X-1471555Y-55330D01*
X-1470085D01*
G01X-1452500Y-170500D02*
X-1452255Y-170450D01*
X-1451975Y-170300D01*
X-1451800Y-170050D01*
X-1451730Y-169700D01*
X-1451800Y-169350D01*
X-1452010Y-169050D01*
X-1452325Y-168900D01*
X-1452675D01*
X-1452885Y-168800D01*
X-1453060Y-168550D01*
X-1453130Y-168200D01*
X-1453025Y-167850D01*
X-1452780Y-167600D01*
X-1452500Y-167500D01*
X-1452220Y-167600D01*
X-1451975Y-167850D01*
X-1451870Y-168200D01*
X-1451940Y-168550D01*
X-1452115Y-168800D01*
X-1452325Y-168900D01*
X-1452675D01*
X-1452990Y-169050D01*
X-1453200Y-169350D01*
X-1453270Y-169700D01*
X-1453200Y-170050D01*
X-1453025Y-170300D01*
X-1452745Y-170450D01*
X-1452500Y-170500D01*
G01X-1453200Y-75280D02*
Y-72280D01*
X-1453620Y-72880D01*
G01Y-75280D02*
X-1452780D01*
G01X-1451065Y-74030D02*
X-1450820Y-73680D01*
X-1450610Y-73480D01*
X-1450330Y-73380D01*
X-1450085Y-73480D01*
X-1449910Y-73680D01*
X-1449770Y-73980D01*
X-1449735Y-74330D01*
X-1449770Y-74630D01*
X-1449910Y-74930D01*
X-1450120Y-75180D01*
X-1450365Y-75280D01*
X-1450645Y-75180D01*
X-1450890Y-74880D01*
X-1451030Y-74430D01*
X-1451065Y-73930D01*
X-1450995Y-73280D01*
X-1450890Y-72930D01*
X-1450715Y-72580D01*
X-1450470Y-72330D01*
X-1450225Y-72280D01*
X-1449980Y-72380D01*
X-1449805Y-72630D01*
G01X-1447600Y-72280D02*
X-1447880Y-72380D01*
X-1448090Y-72630D01*
X-1448230Y-72930D01*
X-1448335Y-73330D01*
X-1448370Y-73780D01*
X-1448335Y-74230D01*
X-1448230Y-74630D01*
X-1448090Y-74930D01*
X-1447880Y-75180D01*
X-1447600Y-75280D01*
X-1447320Y-75180D01*
X-1447110Y-74930D01*
X-1446970Y-74630D01*
X-1446865Y-74230D01*
X-1446830Y-73780D01*
X-1446865Y-73330D01*
X-1446970Y-72930D01*
X-1447110Y-72630D01*
X-1447320Y-72380D01*
X-1447600Y-72280D01*
G01X-1393050Y-143630D02*
X-1393200Y-143840D01*
X-1393300Y-144085D01*
Y-144365D01*
X-1393150Y-144680D01*
X-1392900Y-144925D01*
X-1392600Y-145100D01*
X-1392100Y-145240D01*
X-1391650Y-145275D01*
X-1391200Y-145205D01*
X-1390900Y-145100D01*
X-1390600Y-144890D01*
X-1390400Y-144645D01*
X-1390300Y-144400D01*
Y-144155D01*
X-1390400Y-143910D01*
X-1390550Y-143700D01*
X-1390750Y-143525D01*
G01X-1390900Y-142370D02*
X-1390550Y-142160D01*
X-1390350Y-141880D01*
X-1390300Y-141565D01*
X-1390350Y-141285D01*
X-1390600Y-141005D01*
X-1390900Y-140830D01*
X-1391200Y-140795D01*
X-1391550Y-140865D01*
X-1391800Y-141110D01*
X-1391900Y-141355D01*
Y-141670D01*
G01Y-141355D02*
X-1392050Y-141145D01*
X-1392300Y-140970D01*
X-1392600Y-140900D01*
X-1392900Y-140970D01*
X-1393150Y-141145D01*
X-1393300Y-141460D01*
X-1393250Y-141775D01*
X-1393050Y-142090D01*
G01X-1397850Y-143230D02*
X-1398000Y-143440D01*
X-1398100Y-143685D01*
Y-143965D01*
X-1397950Y-144280D01*
X-1397700Y-144525D01*
X-1397400Y-144700D01*
X-1396900Y-144840D01*
X-1396450Y-144875D01*
X-1396000Y-144805D01*
X-1395700Y-144700D01*
X-1395400Y-144490D01*
X-1395200Y-144245D01*
X-1395100Y-144000D01*
Y-143755D01*
X-1395200Y-143510D01*
X-1395350Y-143300D01*
X-1395550Y-143125D01*
G01X-1397600Y-141865D02*
X-1397900Y-141655D01*
X-1398050Y-141410D01*
X-1398100Y-141130D01*
X-1398000Y-140780D01*
X-1397750Y-140535D01*
X-1397450Y-140465D01*
X-1397150Y-140500D01*
X-1396900Y-140640D01*
X-1396400Y-141340D01*
X-1396050Y-141655D01*
X-1395550Y-141865D01*
X-1395100Y-141935D01*
Y-140465D01*
G01X-1358989Y-99156D02*
X-1358814Y-99456D01*
X-1358604Y-99656D01*
X-1358359Y-99756D01*
X-1358079Y-99656D01*
X-1357869Y-99456D01*
X-1357659Y-99156D01*
X-1357589Y-98756D01*
Y-96756D01*
G01X-1356259Y-99156D02*
X-1356049Y-99506D01*
X-1355769Y-99706D01*
X-1355454Y-99756D01*
X-1355174Y-99706D01*
X-1354894Y-99456D01*
X-1354719Y-99156D01*
X-1354684Y-98856D01*
X-1354754Y-98506D01*
X-1354999Y-98256D01*
X-1355244Y-98156D01*
X-1355559D01*
G01X-1355244D02*
X-1355034Y-98006D01*
X-1354859Y-97756D01*
X-1354789Y-97456D01*
X-1354859Y-97156D01*
X-1355034Y-96906D01*
X-1355349Y-96756D01*
X-1355664Y-96806D01*
X-1355979Y-97006D01*
G01X-1360660Y-21880D02*
X-1363660D01*
Y-21005D01*
X-1363510Y-20725D01*
X-1363310Y-20550D01*
X-1362910Y-20480D01*
X-1362510Y-20550D01*
X-1362260Y-20760D01*
X-1362110Y-21005D01*
Y-21880D01*
G01Y-21005D02*
X-1360660Y-20480D01*
G01Y-18380D02*
X-1363660D01*
X-1363060Y-18800D01*
G01X-1360660D02*
Y-17960D01*
G01Y-15580D02*
X-1363660D01*
X-1363060Y-16000D01*
G01X-1360660D02*
Y-15160D01*
G01X-1350860Y-11760D02*
X-1350560Y-11585D01*
X-1350360Y-11375D01*
X-1350260Y-11130D01*
X-1350360Y-10850D01*
X-1350560Y-10640D01*
X-1350860Y-10430D01*
X-1351260Y-10360D01*
X-1353260D01*
G01X-1352760Y-8925D02*
X-1353060Y-8715D01*
X-1353210Y-8470D01*
X-1353260Y-8190D01*
X-1353160Y-7840D01*
X-1352910Y-7595D01*
X-1352610Y-7525D01*
X-1352310Y-7560D01*
X-1352060Y-7700D01*
X-1351560Y-8400D01*
X-1351210Y-8715D01*
X-1350710Y-8925D01*
X-1350260Y-8995D01*
Y-7525D01*
G01X-1351510Y-6125D02*
X-1351860Y-5880D01*
X-1352060Y-5670D01*
X-1352160Y-5390D01*
X-1352060Y-5145D01*
X-1351860Y-4970D01*
X-1351560Y-4830D01*
X-1351210Y-4795D01*
X-1350910Y-4830D01*
X-1350610Y-4970D01*
X-1350360Y-5180D01*
X-1350260Y-5425D01*
X-1350360Y-5705D01*
X-1350660Y-5950D01*
X-1351110Y-6090D01*
X-1351610Y-6125D01*
X-1352260Y-6055D01*
X-1352610Y-5950D01*
X-1352960Y-5775D01*
X-1353210Y-5530D01*
X-1353260Y-5285D01*
X-1353160Y-5040D01*
X-1352910Y-4865D01*
G01X-1328750Y-86130D02*
X-1328900Y-86340D01*
X-1329000Y-86585D01*
Y-86865D01*
X-1328850Y-87180D01*
X-1328600Y-87425D01*
X-1328300Y-87600D01*
X-1327800Y-87740D01*
X-1327350Y-87775D01*
X-1326900Y-87705D01*
X-1326600Y-87600D01*
X-1326300Y-87390D01*
X-1326100Y-87145D01*
X-1326000Y-86900D01*
Y-86655D01*
X-1326100Y-86410D01*
X-1326250Y-86200D01*
X-1326450Y-86025D01*
G01X-1326000Y-83680D02*
X-1329000D01*
X-1326850Y-84975D01*
Y-83225D01*
G01X-1313600Y-101900D02*
X-1313425Y-102200D01*
X-1313215Y-102400D01*
X-1312970Y-102500D01*
X-1312690Y-102400D01*
X-1312480Y-102200D01*
X-1312270Y-101900D01*
X-1312200Y-101500D01*
Y-99500D01*
G01X-1309680Y-102500D02*
Y-99500D01*
X-1310975Y-101650D01*
X-1309225D01*
G01X-1312750Y-86630D02*
X-1312900Y-86840D01*
X-1313000Y-87085D01*
Y-87365D01*
X-1312850Y-87680D01*
X-1312600Y-87925D01*
X-1312300Y-88100D01*
X-1311800Y-88240D01*
X-1311350Y-88275D01*
X-1310900Y-88205D01*
X-1310600Y-88100D01*
X-1310300Y-87890D01*
X-1310100Y-87645D01*
X-1310000Y-87400D01*
Y-87155D01*
X-1310100Y-86910D01*
X-1310250Y-86700D01*
X-1310450Y-86525D01*
G01X-1310000Y-84600D02*
X-1313000D01*
X-1312400Y-85020D01*
G01X-1310000D02*
Y-84180D01*
G01X-1321500Y-71000D02*
X-1324500D01*
Y-70125D01*
X-1324350Y-69845D01*
X-1324150Y-69670D01*
X-1323750Y-69600D01*
X-1323350Y-69670D01*
X-1323100Y-69880D01*
X-1322950Y-70125D01*
Y-71000D01*
G01Y-70125D02*
X-1321500Y-69600D01*
G01Y-67500D02*
X-1321550Y-67255D01*
X-1321700Y-66975D01*
X-1321950Y-66800D01*
X-1322300Y-66730D01*
X-1322650Y-66800D01*
X-1322950Y-67010D01*
X-1323100Y-67325D01*
Y-67675D01*
X-1323200Y-67885D01*
X-1323450Y-68060D01*
X-1323800Y-68130D01*
X-1324150Y-68025D01*
X-1324400Y-67780D01*
X-1324500Y-67500D01*
X-1324400Y-67220D01*
X-1324150Y-66975D01*
X-1323800Y-66870D01*
X-1323450Y-66940D01*
X-1323200Y-67115D01*
X-1323100Y-67325D01*
Y-67675D01*
X-1322950Y-67990D01*
X-1322650Y-68200D01*
X-1322300Y-68270D01*
X-1321950Y-68200D01*
X-1321700Y-68025D01*
X-1321550Y-67745D01*
X-1321500Y-67500D01*
G01Y-64280D02*
X-1324500D01*
X-1322350Y-65575D01*
Y-63825D01*
G01X-1319180Y-28690D02*
X-1322180D01*
Y-27815D01*
X-1322030Y-27535D01*
X-1321830Y-27360D01*
X-1321430Y-27290D01*
X-1321030Y-27360D01*
X-1320780Y-27570D01*
X-1320630Y-27815D01*
Y-28690D01*
G01Y-27815D02*
X-1319180Y-27290D01*
G01X-1319530Y-25785D02*
X-1319280Y-25540D01*
X-1319180Y-25260D01*
X-1319280Y-24980D01*
X-1319580Y-24735D01*
X-1320030Y-24560D01*
X-1320480Y-24490D01*
X-1321030D01*
X-1321480Y-24560D01*
X-1321880Y-24735D01*
X-1322080Y-24945D01*
X-1322180Y-25190D01*
X-1322080Y-25470D01*
X-1321880Y-25680D01*
X-1321580Y-25820D01*
X-1321180Y-25890D01*
X-1320830Y-25820D01*
X-1320480Y-25645D01*
X-1320280Y-25435D01*
X-1320230Y-25190D01*
X-1320330Y-24910D01*
X-1320580Y-24700D01*
X-1321030Y-24490D01*
G01X-1299300Y-80820D02*
Y-77820D01*
X-1298425D01*
X-1298145Y-77970D01*
X-1297970Y-78170D01*
X-1297900Y-78570D01*
X-1297970Y-78970D01*
X-1298180Y-79220D01*
X-1298425Y-79370D01*
X-1299300D01*
G01X-1298425D02*
X-1297900Y-80820D01*
G01X-1295870D02*
X-1295800Y-80170D01*
X-1295695Y-79620D01*
X-1295555Y-79120D01*
X-1295380Y-78570D01*
X-1295100Y-77820D01*
X-1296500D01*
G01X-1295900Y-69700D02*
Y-66700D01*
X-1295025D01*
X-1294745Y-66850D01*
X-1294570Y-67050D01*
X-1294500Y-67450D01*
X-1294570Y-67850D01*
X-1294780Y-68100D01*
X-1295025Y-68250D01*
X-1295900D01*
G01X-1295025D02*
X-1294500Y-69700D01*
G01X-1292470D02*
X-1292400Y-69050D01*
X-1292295Y-68500D01*
X-1292155Y-68000D01*
X-1291980Y-67450D01*
X-1291700Y-66700D01*
X-1293100D01*
G01X-1290370Y-69250D02*
X-1290160Y-69500D01*
X-1289915Y-69650D01*
X-1289600Y-69700D01*
X-1289285Y-69600D01*
X-1289040Y-69400D01*
X-1288865Y-69050D01*
X-1288830Y-68650D01*
X-1288900Y-68250D01*
X-1289075Y-68000D01*
X-1289320Y-67800D01*
X-1289565Y-67750D01*
X-1289810Y-67800D01*
X-1290125Y-68000D01*
X-1290020Y-66700D01*
X-1289075D01*
G01X-1299440Y-75400D02*
Y-72400D01*
X-1298565D01*
X-1298285Y-72550D01*
X-1298110Y-72750D01*
X-1298040Y-73150D01*
X-1298110Y-73550D01*
X-1298320Y-73800D01*
X-1298565Y-73950D01*
X-1299440D01*
G01X-1298565D02*
X-1298040Y-75400D01*
G01X-1296605Y-74150D02*
X-1296360Y-73800D01*
X-1296150Y-73600D01*
X-1295870Y-73500D01*
X-1295625Y-73600D01*
X-1295450Y-73800D01*
X-1295310Y-74100D01*
X-1295275Y-74450D01*
X-1295310Y-74750D01*
X-1295450Y-75050D01*
X-1295660Y-75300D01*
X-1295905Y-75400D01*
X-1296185Y-75300D01*
X-1296430Y-75000D01*
X-1296570Y-74550D01*
X-1296605Y-74050D01*
X-1296535Y-73400D01*
X-1296430Y-73050D01*
X-1296255Y-72700D01*
X-1296010Y-72450D01*
X-1295765Y-72400D01*
X-1295520Y-72500D01*
X-1295345Y-72750D01*
G01X-1296000Y-64500D02*
Y-61500D01*
X-1295125D01*
X-1294845Y-61650D01*
X-1294670Y-61850D01*
X-1294600Y-62250D01*
X-1294670Y-62650D01*
X-1294880Y-62900D01*
X-1295125Y-63050D01*
X-1296000D01*
G01X-1295125D02*
X-1294600Y-64500D01*
G01X-1292500D02*
X-1292255Y-64450D01*
X-1291975Y-64300D01*
X-1291800Y-64050D01*
X-1291730Y-63700D01*
X-1291800Y-63350D01*
X-1292010Y-63050D01*
X-1292325Y-62900D01*
X-1292675D01*
X-1292885Y-62800D01*
X-1293060Y-62550D01*
X-1293130Y-62200D01*
X-1293025Y-61850D01*
X-1292780Y-61600D01*
X-1292500Y-61500D01*
X-1292220Y-61600D01*
X-1291975Y-61850D01*
X-1291870Y-62200D01*
X-1291940Y-62550D01*
X-1292115Y-62800D01*
X-1292325Y-62900D01*
X-1292675D01*
X-1292990Y-63050D01*
X-1293200Y-63350D01*
X-1293270Y-63700D01*
X-1293200Y-64050D01*
X-1293025Y-64300D01*
X-1292745Y-64450D01*
X-1292500Y-64500D01*
G01X-1289700D02*
Y-61500D01*
X-1290120Y-62100D01*
G01Y-64500D02*
X-1289280D01*
G01X-1296000Y-59500D02*
Y-56500D01*
X-1295125D01*
X-1294845Y-56650D01*
X-1294670Y-56850D01*
X-1294600Y-57250D01*
X-1294670Y-57650D01*
X-1294880Y-57900D01*
X-1295125Y-58050D01*
X-1296000D01*
G01X-1295125D02*
X-1294600Y-59500D01*
G01X-1292500D02*
X-1292255Y-59450D01*
X-1291975Y-59300D01*
X-1291800Y-59050D01*
X-1291730Y-58700D01*
X-1291800Y-58350D01*
X-1292010Y-58050D01*
X-1292325Y-57900D01*
X-1292675D01*
X-1292885Y-57800D01*
X-1293060Y-57550D01*
X-1293130Y-57200D01*
X-1293025Y-56850D01*
X-1292780Y-56600D01*
X-1292500Y-56500D01*
X-1292220Y-56600D01*
X-1291975Y-56850D01*
X-1291870Y-57200D01*
X-1291940Y-57550D01*
X-1292115Y-57800D01*
X-1292325Y-57900D01*
X-1292675D01*
X-1292990Y-58050D01*
X-1293200Y-58350D01*
X-1293270Y-58700D01*
X-1293200Y-59050D01*
X-1293025Y-59300D01*
X-1292745Y-59450D01*
X-1292500Y-59500D01*
G01X-1290365Y-57000D02*
X-1290155Y-56700D01*
X-1289910Y-56550D01*
X-1289630Y-56500D01*
X-1289280Y-56600D01*
X-1289035Y-56850D01*
X-1288965Y-57150D01*
X-1289000Y-57450D01*
X-1289140Y-57700D01*
X-1289840Y-58200D01*
X-1290155Y-58550D01*
X-1290365Y-59050D01*
X-1290435Y-59500D01*
X-1288965D01*
G01X-1296000Y-53500D02*
Y-50500D01*
X-1295125D01*
X-1294845Y-50650D01*
X-1294670Y-50850D01*
X-1294600Y-51250D01*
X-1294670Y-51650D01*
X-1294880Y-51900D01*
X-1295125Y-52050D01*
X-1296000D01*
G01X-1295125D02*
X-1294600Y-53500D01*
G01X-1292570D02*
X-1292500Y-52850D01*
X-1292395Y-52300D01*
X-1292255Y-51800D01*
X-1292080Y-51250D01*
X-1291800Y-50500D01*
X-1293200D01*
G01X-1290365Y-52250D02*
X-1290120Y-51900D01*
X-1289910Y-51700D01*
X-1289630Y-51600D01*
X-1289385Y-51700D01*
X-1289210Y-51900D01*
X-1289070Y-52200D01*
X-1289035Y-52550D01*
X-1289070Y-52850D01*
X-1289210Y-53150D01*
X-1289420Y-53400D01*
X-1289665Y-53500D01*
X-1289945Y-53400D01*
X-1290190Y-53100D01*
X-1290330Y-52650D01*
X-1290365Y-52150D01*
X-1290295Y-51500D01*
X-1290190Y-51150D01*
X-1290015Y-50800D01*
X-1289770Y-50550D01*
X-1289525Y-50500D01*
X-1289280Y-50600D01*
X-1289105Y-50850D01*
G01X-1296000Y-43000D02*
Y-40000D01*
X-1295125D01*
X-1294845Y-40150D01*
X-1294670Y-40350D01*
X-1294600Y-40750D01*
X-1294670Y-41150D01*
X-1294880Y-41400D01*
X-1295125Y-41550D01*
X-1296000D01*
G01X-1295125D02*
X-1294600Y-43000D01*
G01X-1292500D02*
X-1292255Y-42950D01*
X-1291975Y-42800D01*
X-1291800Y-42550D01*
X-1291730Y-42200D01*
X-1291800Y-41850D01*
X-1292010Y-41550D01*
X-1292325Y-41400D01*
X-1292675D01*
X-1292885Y-41300D01*
X-1293060Y-41050D01*
X-1293130Y-40700D01*
X-1293025Y-40350D01*
X-1292780Y-40100D01*
X-1292500Y-40000D01*
X-1292220Y-40100D01*
X-1291975Y-40350D01*
X-1291870Y-40700D01*
X-1291940Y-41050D01*
X-1292115Y-41300D01*
X-1292325Y-41400D01*
X-1292675D01*
X-1292990Y-41550D01*
X-1293200Y-41850D01*
X-1293270Y-42200D01*
X-1293200Y-42550D01*
X-1293025Y-42800D01*
X-1292745Y-42950D01*
X-1292500Y-43000D01*
G01X-1290470Y-42400D02*
X-1290260Y-42750D01*
X-1289980Y-42950D01*
X-1289665Y-43000D01*
X-1289385Y-42950D01*
X-1289105Y-42700D01*
X-1288930Y-42400D01*
X-1288895Y-42100D01*
X-1288965Y-41750D01*
X-1289210Y-41500D01*
X-1289455Y-41400D01*
X-1289770D01*
G01X-1289455D02*
X-1289245Y-41250D01*
X-1289070Y-41000D01*
X-1289000Y-40700D01*
X-1289070Y-40400D01*
X-1289245Y-40150D01*
X-1289560Y-40000D01*
X-1289875Y-40050D01*
X-1290190Y-40250D01*
G01X-1295860Y-47840D02*
Y-44840D01*
X-1294985D01*
X-1294705Y-44990D01*
X-1294530Y-45190D01*
X-1294460Y-45590D01*
X-1294530Y-45990D01*
X-1294740Y-46240D01*
X-1294985Y-46390D01*
X-1295860D01*
G01X-1294985D02*
X-1294460Y-47840D01*
G01X-1292430D02*
X-1292360Y-47190D01*
X-1292255Y-46640D01*
X-1292115Y-46140D01*
X-1291940Y-45590D01*
X-1291660Y-44840D01*
X-1293060D01*
G01X-1289630Y-47840D02*
X-1289560Y-47190D01*
X-1289455Y-46640D01*
X-1289315Y-46140D01*
X-1289140Y-45590D01*
X-1288860Y-44840D01*
X-1290260D01*
G01X-1296000Y-31000D02*
Y-28000D01*
X-1295125D01*
X-1294845Y-28150D01*
X-1294670Y-28350D01*
X-1294600Y-28750D01*
X-1294670Y-29150D01*
X-1294880Y-29400D01*
X-1295125Y-29550D01*
X-1296000D01*
G01X-1295125D02*
X-1294600Y-31000D01*
G01X-1292570D02*
X-1292500Y-30350D01*
X-1292395Y-29800D01*
X-1292255Y-29300D01*
X-1292080Y-28750D01*
X-1291800Y-28000D01*
X-1293200D01*
G01X-1290295Y-30650D02*
X-1290050Y-30900D01*
X-1289770Y-31000D01*
X-1289490Y-30900D01*
X-1289245Y-30600D01*
X-1289070Y-30150D01*
X-1289000Y-29700D01*
Y-29150D01*
X-1289070Y-28700D01*
X-1289245Y-28300D01*
X-1289455Y-28100D01*
X-1289700Y-28000D01*
X-1289980Y-28100D01*
X-1290190Y-28300D01*
X-1290330Y-28600D01*
X-1290400Y-29000D01*
X-1290330Y-29350D01*
X-1290155Y-29700D01*
X-1289945Y-29900D01*
X-1289700Y-29950D01*
X-1289420Y-29850D01*
X-1289210Y-29600D01*
X-1289000Y-29150D01*
G01X-1296000Y-37500D02*
Y-34500D01*
X-1295125D01*
X-1294845Y-34650D01*
X-1294670Y-34850D01*
X-1294600Y-35250D01*
X-1294670Y-35650D01*
X-1294880Y-35900D01*
X-1295125Y-36050D01*
X-1296000D01*
G01X-1295125D02*
X-1294600Y-37500D01*
G01X-1292570D02*
X-1292500Y-36850D01*
X-1292395Y-36300D01*
X-1292255Y-35800D01*
X-1292080Y-35250D01*
X-1291800Y-34500D01*
X-1293200D01*
G01X-1289700Y-37500D02*
X-1289455Y-37450D01*
X-1289175Y-37300D01*
X-1289000Y-37050D01*
X-1288930Y-36700D01*
X-1289000Y-36350D01*
X-1289210Y-36050D01*
X-1289525Y-35900D01*
X-1289875D01*
X-1290085Y-35800D01*
X-1290260Y-35550D01*
X-1290330Y-35200D01*
X-1290225Y-34850D01*
X-1289980Y-34600D01*
X-1289700Y-34500D01*
X-1289420Y-34600D01*
X-1289175Y-34850D01*
X-1289070Y-35200D01*
X-1289140Y-35550D01*
X-1289315Y-35800D01*
X-1289525Y-35900D01*
X-1289875D01*
X-1290190Y-36050D01*
X-1290400Y-36350D01*
X-1290470Y-36700D01*
X-1290400Y-37050D01*
X-1290225Y-37300D01*
X-1289945Y-37450D01*
X-1289700Y-37500D01*
G01X-1282280Y-188690D02*
X-1282105Y-188990D01*
X-1281895Y-189190D01*
X-1281650Y-189290D01*
X-1281370Y-189190D01*
X-1281160Y-188990D01*
X-1280950Y-188690D01*
X-1280880Y-188290D01*
Y-186290D01*
G01X-1278780Y-189290D02*
X-1278535Y-189240D01*
X-1278255Y-189090D01*
X-1278080Y-188840D01*
X-1278010Y-188490D01*
X-1278080Y-188140D01*
X-1278290Y-187840D01*
X-1278605Y-187690D01*
X-1278955D01*
X-1279165Y-187590D01*
X-1279340Y-187340D01*
X-1279410Y-186990D01*
X-1279305Y-186640D01*
X-1279060Y-186390D01*
X-1278780Y-186290D01*
X-1278500Y-186390D01*
X-1278255Y-186640D01*
X-1278150Y-186990D01*
X-1278220Y-187340D01*
X-1278395Y-187590D01*
X-1278605Y-187690D01*
X-1278955D01*
X-1279270Y-187840D01*
X-1279480Y-188140D01*
X-1279550Y-188490D01*
X-1279480Y-188840D01*
X-1279305Y-189090D01*
X-1279025Y-189240D01*
X-1278780Y-189290D01*
G01X-1278815Y-167950D02*
X-1278605Y-167650D01*
X-1278360Y-167500D01*
X-1278080Y-167450D01*
X-1277730Y-167550D01*
X-1277485Y-167800D01*
X-1277415Y-168100D01*
X-1277450Y-168400D01*
X-1277590Y-168650D01*
X-1278290Y-169150D01*
X-1278605Y-169500D01*
X-1278815Y-170000D01*
X-1278885Y-170450D01*
X-1277415D01*
G01X-1275350Y-167450D02*
X-1275630Y-167550D01*
X-1275840Y-167800D01*
X-1275980Y-168100D01*
X-1276085Y-168500D01*
X-1276120Y-168950D01*
X-1276085Y-169400D01*
X-1275980Y-169800D01*
X-1275840Y-170100D01*
X-1275630Y-170350D01*
X-1275350Y-170450D01*
X-1275070Y-170350D01*
X-1274860Y-170100D01*
X-1274720Y-169800D01*
X-1274615Y-169400D01*
X-1274580Y-168950D01*
X-1274615Y-168500D01*
X-1274720Y-168100D01*
X-1274860Y-167800D01*
X-1275070Y-167550D01*
X-1275350Y-167450D01*
G01X-1287188Y-159676D02*
X-1286978Y-160026D01*
X-1286698Y-160226D01*
X-1286382Y-160276D01*
X-1286102Y-160226D01*
X-1285822Y-159976D01*
X-1285648Y-159676D01*
X-1285613Y-159376D01*
X-1285683Y-159026D01*
X-1285928Y-158776D01*
X-1286173Y-158676D01*
X-1286488D01*
G01X-1286173D02*
X-1285963Y-158526D01*
X-1285787Y-158276D01*
X-1285718Y-157976D01*
X-1285787Y-157676D01*
X-1285963Y-157426D01*
X-1286278Y-157276D01*
X-1286593Y-157326D01*
X-1286908Y-157526D01*
G01X-1279590Y-156150D02*
Y-153150D01*
X-1280010Y-153750D01*
G01Y-156150D02*
X-1279170D01*
G01X-1277385Y-155800D02*
X-1277140Y-156050D01*
X-1276860Y-156150D01*
X-1276580Y-156050D01*
X-1276335Y-155750D01*
X-1276160Y-155300D01*
X-1276090Y-154850D01*
Y-154300D01*
X-1276160Y-153850D01*
X-1276335Y-153450D01*
X-1276545Y-153250D01*
X-1276790Y-153150D01*
X-1277070Y-153250D01*
X-1277280Y-153450D01*
X-1277420Y-153750D01*
X-1277490Y-154150D01*
X-1277420Y-154500D01*
X-1277245Y-154850D01*
X-1277035Y-155050D01*
X-1276790Y-155100D01*
X-1276510Y-155000D01*
X-1276300Y-154750D01*
X-1276090Y-154300D01*
G01X-1287083Y-125280D02*
X-1286873Y-124980D01*
X-1286628Y-124830D01*
X-1286348Y-124780D01*
X-1285998Y-124880D01*
X-1285752Y-125130D01*
X-1285683Y-125429D01*
X-1285718Y-125730D01*
X-1285858Y-125980D01*
X-1286558Y-126480D01*
X-1286873Y-126830D01*
X-1287083Y-127330D01*
X-1287153Y-127780D01*
X-1285683D01*
G01X-1288560Y-17330D02*
X-1288260Y-17155D01*
X-1288060Y-16945D01*
X-1287960Y-16700D01*
X-1288060Y-16420D01*
X-1288260Y-16210D01*
X-1288560Y-16000D01*
X-1288960Y-15930D01*
X-1290960D01*
G01X-1290460Y-14495D02*
X-1290760Y-14285D01*
X-1290910Y-14040D01*
X-1290960Y-13760D01*
X-1290860Y-13410D01*
X-1290610Y-13165D01*
X-1290310Y-13095D01*
X-1290010Y-13130D01*
X-1289760Y-13270D01*
X-1289260Y-13970D01*
X-1288910Y-14285D01*
X-1288410Y-14495D01*
X-1287960Y-14565D01*
Y-13095D01*
G01X-1288410Y-11800D02*
X-1288160Y-11590D01*
X-1288010Y-11345D01*
X-1287960Y-11030D01*
X-1288060Y-10715D01*
X-1288260Y-10470D01*
X-1288610Y-10295D01*
X-1289010Y-10260D01*
X-1289410Y-10330D01*
X-1289660Y-10505D01*
X-1289860Y-10750D01*
X-1289910Y-10995D01*
X-1289860Y-11240D01*
X-1289660Y-11555D01*
X-1290960Y-11450D01*
Y-10505D01*
G01X-1200000Y-560000D02*
X-890000D01*
G01Y-520000D02*
X-1200000D01*
G01X-575000Y-480000D02*
X-1200000D01*
G01X-1214590Y-188620D02*
X-1214415Y-188920D01*
X-1214205Y-189120D01*
X-1213960Y-189220D01*
X-1213680Y-189120D01*
X-1213470Y-188920D01*
X-1213260Y-188620D01*
X-1213190Y-188220D01*
Y-186220D01*
G01X-1211685Y-188870D02*
X-1211440Y-189120D01*
X-1211160Y-189220D01*
X-1210880Y-189120D01*
X-1210635Y-188820D01*
X-1210460Y-188370D01*
X-1210390Y-187920D01*
Y-187370D01*
X-1210460Y-186920D01*
X-1210635Y-186520D01*
X-1210845Y-186320D01*
X-1211090Y-186220D01*
X-1211370Y-186320D01*
X-1211580Y-186520D01*
X-1211720Y-186820D01*
X-1211790Y-187220D01*
X-1211720Y-187570D01*
X-1211545Y-187920D01*
X-1211335Y-188120D01*
X-1211090Y-188170D01*
X-1210810Y-188070D01*
X-1210600Y-187820D01*
X-1210390Y-187370D01*
G01X-1201000Y-42000D02*
Y-39000D01*
X-1200125D01*
X-1199845Y-39150D01*
X-1199670Y-39350D01*
X-1199600Y-39750D01*
X-1199670Y-40150D01*
X-1199880Y-40400D01*
X-1200125Y-40550D01*
X-1201000D01*
G01X-1200125D02*
X-1199600Y-42000D01*
G01X-1197500D02*
Y-39000D01*
X-1197920Y-39600D01*
G01Y-42000D02*
X-1197080D01*
G01X-1195365Y-39500D02*
X-1195155Y-39200D01*
X-1194910Y-39050D01*
X-1194630Y-39000D01*
X-1194280Y-39100D01*
X-1194035Y-39350D01*
X-1193965Y-39650D01*
X-1194000Y-39950D01*
X-1194140Y-40200D01*
X-1194840Y-40700D01*
X-1195155Y-41050D01*
X-1195365Y-41550D01*
X-1195435Y-42000D01*
X-1193965D01*
G01X-1201000Y-48000D02*
Y-45000D01*
X-1200125D01*
X-1199845Y-45150D01*
X-1199670Y-45350D01*
X-1199600Y-45750D01*
X-1199670Y-46150D01*
X-1199880Y-46400D01*
X-1200125Y-46550D01*
X-1201000D01*
G01X-1200125D02*
X-1199600Y-48000D01*
G01X-1197500D02*
X-1197255Y-47950D01*
X-1196975Y-47800D01*
X-1196800Y-47550D01*
X-1196730Y-47200D01*
X-1196800Y-46850D01*
X-1197010Y-46550D01*
X-1197325Y-46400D01*
X-1197675D01*
X-1197885Y-46300D01*
X-1198060Y-46050D01*
X-1198130Y-45700D01*
X-1198025Y-45350D01*
X-1197780Y-45100D01*
X-1197500Y-45000D01*
X-1197220Y-45100D01*
X-1196975Y-45350D01*
X-1196870Y-45700D01*
X-1196940Y-46050D01*
X-1197115Y-46300D01*
X-1197325Y-46400D01*
X-1197675D01*
X-1197990Y-46550D01*
X-1198200Y-46850D01*
X-1198270Y-47200D01*
X-1198200Y-47550D01*
X-1198025Y-47800D01*
X-1197745Y-47950D01*
X-1197500Y-48000D01*
G01X-1194700Y-45000D02*
X-1194980Y-45100D01*
X-1195190Y-45350D01*
X-1195330Y-45650D01*
X-1195435Y-46050D01*
X-1195470Y-46500D01*
X-1195435Y-46950D01*
X-1195330Y-47350D01*
X-1195190Y-47650D01*
X-1194980Y-47900D01*
X-1194700Y-48000D01*
X-1194420Y-47900D01*
X-1194210Y-47650D01*
X-1194070Y-47350D01*
X-1193965Y-46950D01*
X-1193930Y-46500D01*
X-1193965Y-46050D01*
X-1194070Y-45650D01*
X-1194210Y-45350D01*
X-1194420Y-45100D01*
X-1194700Y-45000D01*
G01X-1201100Y-30500D02*
Y-27500D01*
X-1200225D01*
X-1199945Y-27650D01*
X-1199770Y-27850D01*
X-1199700Y-28250D01*
X-1199770Y-28650D01*
X-1199980Y-28900D01*
X-1200225Y-29050D01*
X-1201100D01*
G01X-1200225D02*
X-1199700Y-30500D01*
G01X-1197180D02*
Y-27500D01*
X-1198475Y-29650D01*
X-1196725D01*
G01X-1201500Y-25000D02*
Y-22000D01*
X-1200625D01*
X-1200345Y-22150D01*
X-1200170Y-22350D01*
X-1200100Y-22750D01*
X-1200170Y-23150D01*
X-1200380Y-23400D01*
X-1200625Y-23550D01*
X-1201500D01*
G01X-1200625D02*
X-1200100Y-25000D01*
G01X-1198665Y-22500D02*
X-1198455Y-22200D01*
X-1198210Y-22050D01*
X-1197930Y-22000D01*
X-1197580Y-22100D01*
X-1197335Y-22350D01*
X-1197265Y-22650D01*
X-1197300Y-22950D01*
X-1197440Y-23200D01*
X-1198140Y-23700D01*
X-1198455Y-24050D01*
X-1198665Y-24550D01*
X-1198735Y-25000D01*
X-1197265D01*
G01X-1194780D02*
Y-22000D01*
X-1196075Y-24150D01*
X-1194325D01*
G01X-1201100Y-36500D02*
Y-33500D01*
X-1200225D01*
X-1199945Y-33650D01*
X-1199770Y-33850D01*
X-1199700Y-34250D01*
X-1199770Y-34650D01*
X-1199980Y-34900D01*
X-1200225Y-35050D01*
X-1201100D01*
G01X-1200225D02*
X-1199700Y-36500D01*
G01X-1198370Y-36050D02*
X-1198160Y-36300D01*
X-1197915Y-36450D01*
X-1197600Y-36500D01*
X-1197285Y-36400D01*
X-1197040Y-36200D01*
X-1196865Y-35850D01*
X-1196830Y-35450D01*
X-1196900Y-35050D01*
X-1197075Y-34800D01*
X-1197320Y-34600D01*
X-1197565Y-34550D01*
X-1197810Y-34600D01*
X-1198125Y-34800D01*
X-1198020Y-33500D01*
X-1197075D01*
G01X-1201500Y-19500D02*
Y-16500D01*
X-1200625D01*
X-1200345Y-16650D01*
X-1200170Y-16850D01*
X-1200100Y-17250D01*
X-1200170Y-17650D01*
X-1200380Y-17900D01*
X-1200625Y-18050D01*
X-1201500D01*
G01X-1200625D02*
X-1200100Y-19500D01*
G01X-1198665Y-17000D02*
X-1198455Y-16700D01*
X-1198210Y-16550D01*
X-1197930Y-16500D01*
X-1197580Y-16600D01*
X-1197335Y-16850D01*
X-1197265Y-17150D01*
X-1197300Y-17450D01*
X-1197440Y-17700D01*
X-1198140Y-18200D01*
X-1198455Y-18550D01*
X-1198665Y-19050D01*
X-1198735Y-19500D01*
X-1197265D01*
G01X-1195970Y-19050D02*
X-1195760Y-19300D01*
X-1195515Y-19450D01*
X-1195200Y-19500D01*
X-1194885Y-19400D01*
X-1194640Y-19200D01*
X-1194465Y-18850D01*
X-1194430Y-18450D01*
X-1194500Y-18050D01*
X-1194675Y-17800D01*
X-1194920Y-17600D01*
X-1195165Y-17550D01*
X-1195410Y-17600D01*
X-1195725Y-17800D01*
X-1195620Y-16500D01*
X-1194675D01*
G01X-1201500Y-7000D02*
Y-4000D01*
X-1200625D01*
X-1200345Y-4150D01*
X-1200170Y-4350D01*
X-1200100Y-4750D01*
X-1200170Y-5150D01*
X-1200380Y-5400D01*
X-1200625Y-5550D01*
X-1201500D01*
G01X-1200625D02*
X-1200100Y-7000D01*
G01X-1198000D02*
Y-4000D01*
X-1198420Y-4600D01*
G01Y-7000D02*
X-1197580D01*
G01X-1195970Y-6550D02*
X-1195760Y-6800D01*
X-1195515Y-6950D01*
X-1195200Y-7000D01*
X-1194885Y-6900D01*
X-1194640Y-6700D01*
X-1194465Y-6350D01*
X-1194430Y-5950D01*
X-1194500Y-5550D01*
X-1194675Y-5300D01*
X-1194920Y-5100D01*
X-1195165Y-5050D01*
X-1195410Y-5100D01*
X-1195725Y-5300D01*
X-1195620Y-4000D01*
X-1194675D01*
G01X-1201500Y-13500D02*
Y-10500D01*
X-1200625D01*
X-1200345Y-10650D01*
X-1200170Y-10850D01*
X-1200100Y-11250D01*
X-1200170Y-11650D01*
X-1200380Y-11900D01*
X-1200625Y-12050D01*
X-1201500D01*
G01X-1200625D02*
X-1200100Y-13500D01*
G01X-1198665Y-11000D02*
X-1198455Y-10700D01*
X-1198210Y-10550D01*
X-1197930Y-10500D01*
X-1197580Y-10600D01*
X-1197335Y-10850D01*
X-1197265Y-11150D01*
X-1197300Y-11450D01*
X-1197440Y-11700D01*
X-1198140Y-12200D01*
X-1198455Y-12550D01*
X-1198665Y-13050D01*
X-1198735Y-13500D01*
X-1197265D01*
G01X-1195270D02*
X-1195200Y-12850D01*
X-1195095Y-12300D01*
X-1194955Y-11800D01*
X-1194780Y-11250D01*
X-1194500Y-10500D01*
X-1195900D01*
G01X-1201600Y-1500D02*
Y1500D01*
X-1200725D01*
X-1200445Y1350D01*
X-1200270Y1150D01*
X-1200200Y750D01*
X-1200270Y350D01*
X-1200480Y100D01*
X-1200725Y-50D01*
X-1201600D01*
G01X-1200725D02*
X-1200200Y-1500D01*
G01X-1198765Y1000D02*
X-1198555Y1300D01*
X-1198310Y1450D01*
X-1198030Y1500D01*
X-1197680Y1400D01*
X-1197435Y1150D01*
X-1197365Y850D01*
X-1197400Y550D01*
X-1197540Y300D01*
X-1198240Y-200D01*
X-1198555Y-550D01*
X-1198765Y-1050D01*
X-1198835Y-1500D01*
X-1197365D01*
G01X-1195895Y-1150D02*
X-1195650Y-1400D01*
X-1195370Y-1500D01*
X-1195090Y-1400D01*
X-1194845Y-1100D01*
X-1194670Y-650D01*
X-1194600Y-200D01*
Y350D01*
X-1194670Y800D01*
X-1194845Y1200D01*
X-1195055Y1400D01*
X-1195300Y1500D01*
X-1195580Y1400D01*
X-1195790Y1200D01*
X-1195930Y900D01*
X-1196000Y500D01*
X-1195930Y150D01*
X-1195755Y-200D01*
X-1195545Y-400D01*
X-1195300Y-450D01*
X-1195020Y-350D01*
X-1194810Y-100D01*
X-1194600Y350D01*
G01X-1189600Y-112400D02*
X-1189425Y-112700D01*
X-1189215Y-112900D01*
X-1188970Y-113000D01*
X-1188690Y-112900D01*
X-1188480Y-112700D01*
X-1188270Y-112400D01*
X-1188200Y-112000D01*
Y-110000D01*
G01X-1186170Y-113000D02*
X-1186100Y-112350D01*
X-1185995Y-111800D01*
X-1185855Y-111300D01*
X-1185680Y-110750D01*
X-1185400Y-110000D01*
X-1186800D01*
G01X-1157600Y-39500D02*
Y-36500D01*
X-1156725D01*
X-1156445Y-36650D01*
X-1156270Y-36850D01*
X-1156200Y-37250D01*
X-1156270Y-37650D01*
X-1156480Y-37900D01*
X-1156725Y-38050D01*
X-1157600D01*
G01X-1156725D02*
X-1156200Y-39500D01*
G01X-1154870Y-38900D02*
X-1154660Y-39250D01*
X-1154380Y-39450D01*
X-1154065Y-39500D01*
X-1153785Y-39450D01*
X-1153505Y-39200D01*
X-1153330Y-38900D01*
X-1153295Y-38600D01*
X-1153365Y-38250D01*
X-1153610Y-38000D01*
X-1153855Y-37900D01*
X-1154170D01*
G01X-1153855D02*
X-1153645Y-37750D01*
X-1153470Y-37500D01*
X-1153400Y-37200D01*
X-1153470Y-36900D01*
X-1153645Y-36650D01*
X-1153960Y-36500D01*
X-1154275Y-36550D01*
X-1154590Y-36750D01*
G01X-1157500Y-50500D02*
Y-47500D01*
X-1156625D01*
X-1156345Y-47650D01*
X-1156170Y-47850D01*
X-1156100Y-48250D01*
X-1156170Y-48650D01*
X-1156380Y-48900D01*
X-1156625Y-49050D01*
X-1157500D01*
G01X-1156625D02*
X-1156100Y-50500D01*
G01X-1154665Y-48000D02*
X-1154455Y-47700D01*
X-1154210Y-47550D01*
X-1153930Y-47500D01*
X-1153580Y-47600D01*
X-1153335Y-47850D01*
X-1153265Y-48150D01*
X-1153300Y-48450D01*
X-1153440Y-48700D01*
X-1154140Y-49200D01*
X-1154455Y-49550D01*
X-1154665Y-50050D01*
X-1154735Y-50500D01*
X-1153265D01*
G01X-1151865Y-49250D02*
X-1151620Y-48900D01*
X-1151410Y-48700D01*
X-1151130Y-48600D01*
X-1150885Y-48700D01*
X-1150710Y-48900D01*
X-1150570Y-49200D01*
X-1150535Y-49550D01*
X-1150570Y-49850D01*
X-1150710Y-50150D01*
X-1150920Y-50400D01*
X-1151165Y-50500D01*
X-1151445Y-50400D01*
X-1151690Y-50100D01*
X-1151830Y-49650D01*
X-1151865Y-49150D01*
X-1151795Y-48500D01*
X-1151690Y-48150D01*
X-1151515Y-47800D01*
X-1151270Y-47550D01*
X-1151025Y-47500D01*
X-1150780Y-47600D01*
X-1150605Y-47850D01*
G01X-1157500Y-45000D02*
Y-42000D01*
X-1156625D01*
X-1156345Y-42150D01*
X-1156170Y-42350D01*
X-1156100Y-42750D01*
X-1156170Y-43150D01*
X-1156380Y-43400D01*
X-1156625Y-43550D01*
X-1157500D01*
G01X-1156625D02*
X-1156100Y-45000D01*
G01X-1154665Y-42500D02*
X-1154455Y-42200D01*
X-1154210Y-42050D01*
X-1153930Y-42000D01*
X-1153580Y-42100D01*
X-1153335Y-42350D01*
X-1153265Y-42650D01*
X-1153300Y-42950D01*
X-1153440Y-43200D01*
X-1154140Y-43700D01*
X-1154455Y-44050D01*
X-1154665Y-44550D01*
X-1154735Y-45000D01*
X-1153265D01*
G01X-1151200D02*
X-1150955Y-44950D01*
X-1150675Y-44800D01*
X-1150500Y-44550D01*
X-1150430Y-44200D01*
X-1150500Y-43850D01*
X-1150710Y-43550D01*
X-1151025Y-43400D01*
X-1151375D01*
X-1151585Y-43300D01*
X-1151760Y-43050D01*
X-1151830Y-42700D01*
X-1151725Y-42350D01*
X-1151480Y-42100D01*
X-1151200Y-42000D01*
X-1150920Y-42100D01*
X-1150675Y-42350D01*
X-1150570Y-42700D01*
X-1150640Y-43050D01*
X-1150815Y-43300D01*
X-1151025Y-43400D01*
X-1151375D01*
X-1151690Y-43550D01*
X-1151900Y-43850D01*
X-1151970Y-44200D01*
X-1151900Y-44550D01*
X-1151725Y-44800D01*
X-1151445Y-44950D01*
X-1151200Y-45000D01*
G01X-1157410Y-24320D02*
Y-21320D01*
X-1156535D01*
X-1156255Y-21470D01*
X-1156080Y-21670D01*
X-1156010Y-22070D01*
X-1156080Y-22470D01*
X-1156290Y-22720D01*
X-1156535Y-22870D01*
X-1157410D01*
G01X-1156535D02*
X-1156010Y-24320D01*
G01X-1154575Y-21820D02*
X-1154365Y-21520D01*
X-1154120Y-21370D01*
X-1153840Y-21320D01*
X-1153490Y-21420D01*
X-1153245Y-21670D01*
X-1153175Y-21970D01*
X-1153210Y-22270D01*
X-1153350Y-22520D01*
X-1154050Y-23020D01*
X-1154365Y-23370D01*
X-1154575Y-23870D01*
X-1154645Y-24320D01*
X-1153175D01*
G01X-1151880Y-23720D02*
X-1151670Y-24070D01*
X-1151390Y-24270D01*
X-1151075Y-24320D01*
X-1150795Y-24270D01*
X-1150515Y-24020D01*
X-1150340Y-23720D01*
X-1150305Y-23420D01*
X-1150375Y-23070D01*
X-1150620Y-22820D01*
X-1150865Y-22720D01*
X-1151180D01*
G01X-1150865D02*
X-1150655Y-22570D01*
X-1150480Y-22320D01*
X-1150410Y-22020D01*
X-1150480Y-21720D01*
X-1150655Y-21470D01*
X-1150970Y-21320D01*
X-1151285Y-21370D01*
X-1151600Y-21570D01*
G01X-1157600Y-34000D02*
Y-31000D01*
X-1156725D01*
X-1156445Y-31150D01*
X-1156270Y-31350D01*
X-1156200Y-31750D01*
X-1156270Y-32150D01*
X-1156480Y-32400D01*
X-1156725Y-32550D01*
X-1157600D01*
G01X-1156725D02*
X-1156200Y-34000D01*
G01X-1154765Y-31500D02*
X-1154555Y-31200D01*
X-1154310Y-31050D01*
X-1154030Y-31000D01*
X-1153680Y-31100D01*
X-1153435Y-31350D01*
X-1153365Y-31650D01*
X-1153400Y-31950D01*
X-1153540Y-32200D01*
X-1154240Y-32700D01*
X-1154555Y-33050D01*
X-1154765Y-33550D01*
X-1154835Y-34000D01*
X-1153365D01*
G01X-1157410Y-29320D02*
Y-26320D01*
X-1156535D01*
X-1156255Y-26470D01*
X-1156080Y-26670D01*
X-1156010Y-27070D01*
X-1156080Y-27470D01*
X-1156290Y-27720D01*
X-1156535Y-27870D01*
X-1157410D01*
G01X-1156535D02*
X-1156010Y-29320D01*
G01X-1154575Y-26820D02*
X-1154365Y-26520D01*
X-1154120Y-26370D01*
X-1153840Y-26320D01*
X-1153490Y-26420D01*
X-1153245Y-26670D01*
X-1153175Y-26970D01*
X-1153210Y-27270D01*
X-1153350Y-27520D01*
X-1154050Y-28020D01*
X-1154365Y-28370D01*
X-1154575Y-28870D01*
X-1154645Y-29320D01*
X-1153175D01*
G01X-1151775Y-26820D02*
X-1151565Y-26520D01*
X-1151320Y-26370D01*
X-1151040Y-26320D01*
X-1150690Y-26420D01*
X-1150445Y-26670D01*
X-1150375Y-26970D01*
X-1150410Y-27270D01*
X-1150550Y-27520D01*
X-1151250Y-28020D01*
X-1151565Y-28370D01*
X-1151775Y-28870D01*
X-1151845Y-29320D01*
X-1150375D01*
G01X-1157500Y-12500D02*
Y-9500D01*
X-1156625D01*
X-1156345Y-9650D01*
X-1156170Y-9850D01*
X-1156100Y-10250D01*
X-1156170Y-10650D01*
X-1156380Y-10900D01*
X-1156625Y-11050D01*
X-1157500D01*
G01X-1156625D02*
X-1156100Y-12500D01*
G01X-1154665Y-10000D02*
X-1154455Y-9700D01*
X-1154210Y-9550D01*
X-1153930Y-9500D01*
X-1153580Y-9600D01*
X-1153335Y-9850D01*
X-1153265Y-10150D01*
X-1153300Y-10450D01*
X-1153440Y-10700D01*
X-1154140Y-11200D01*
X-1154455Y-11550D01*
X-1154665Y-12050D01*
X-1154735Y-12500D01*
X-1153265D01*
G01X-1151200D02*
Y-9500D01*
X-1151620Y-10100D01*
G01Y-12500D02*
X-1150780D01*
G01X-1157500Y-7000D02*
Y-4000D01*
X-1156625D01*
X-1156345Y-4150D01*
X-1156170Y-4350D01*
X-1156100Y-4750D01*
X-1156170Y-5150D01*
X-1156380Y-5400D01*
X-1156625Y-5550D01*
X-1157500D01*
G01X-1156625D02*
X-1156100Y-7000D01*
G01X-1154000D02*
Y-4000D01*
X-1154420Y-4600D01*
G01Y-7000D02*
X-1153580D01*
G01X-1151200D02*
X-1150955Y-6950D01*
X-1150675Y-6800D01*
X-1150500Y-6550D01*
X-1150430Y-6200D01*
X-1150500Y-5850D01*
X-1150710Y-5550D01*
X-1151025Y-5400D01*
X-1151375D01*
X-1151585Y-5300D01*
X-1151760Y-5050D01*
X-1151830Y-4700D01*
X-1151725Y-4350D01*
X-1151480Y-4100D01*
X-1151200Y-4000D01*
X-1150920Y-4100D01*
X-1150675Y-4350D01*
X-1150570Y-4700D01*
X-1150640Y-5050D01*
X-1150815Y-5300D01*
X-1151025Y-5400D01*
X-1151375D01*
X-1151690Y-5550D01*
X-1151900Y-5850D01*
X-1151970Y-6200D01*
X-1151900Y-6550D01*
X-1151725Y-6800D01*
X-1151445Y-6950D01*
X-1151200Y-7000D01*
G01X-1157350Y-19680D02*
Y-16680D01*
X-1156475D01*
X-1156195Y-16830D01*
X-1156020Y-17030D01*
X-1155950Y-17430D01*
X-1156020Y-17830D01*
X-1156230Y-18080D01*
X-1156475Y-18230D01*
X-1157350D01*
G01X-1156475D02*
X-1155950Y-19680D01*
G01X-1154515Y-17180D02*
X-1154305Y-16880D01*
X-1154060Y-16730D01*
X-1153780Y-16680D01*
X-1153430Y-16780D01*
X-1153185Y-17030D01*
X-1153115Y-17330D01*
X-1153150Y-17630D01*
X-1153290Y-17880D01*
X-1153990Y-18380D01*
X-1154305Y-18730D01*
X-1154515Y-19230D01*
X-1154585Y-19680D01*
X-1153115D01*
G01X-1151050Y-16680D02*
X-1151330Y-16780D01*
X-1151540Y-17030D01*
X-1151680Y-17330D01*
X-1151785Y-17730D01*
X-1151820Y-18180D01*
X-1151785Y-18630D01*
X-1151680Y-19030D01*
X-1151540Y-19330D01*
X-1151330Y-19580D01*
X-1151050Y-19680D01*
X-1150770Y-19580D01*
X-1150560Y-19330D01*
X-1150420Y-19030D01*
X-1150315Y-18630D01*
X-1150280Y-18180D01*
X-1150315Y-17730D01*
X-1150420Y-17330D01*
X-1150560Y-17030D01*
X-1150770Y-16780D01*
X-1151050Y-16680D01*
G01X-1150775Y-179500D02*
X-1149900Y-176500D01*
X-1149025Y-179500D01*
G01X-1149340Y-178450D02*
X-1150460D01*
G01X-1147100Y-179500D02*
Y-176500D01*
X-1147520Y-177100D01*
G01Y-179500D02*
X-1146680D01*
G01X-1144390Y-155380D02*
X-1144215Y-155680D01*
X-1144005Y-155880D01*
X-1143760Y-155980D01*
X-1143480Y-155880D01*
X-1143270Y-155680D01*
X-1143060Y-155380D01*
X-1142990Y-154980D01*
Y-152980D01*
G01X-1141660Y-155530D02*
X-1141450Y-155780D01*
X-1141205Y-155930D01*
X-1140890Y-155980D01*
X-1140575Y-155880D01*
X-1140330Y-155680D01*
X-1140155Y-155330D01*
X-1140120Y-154930D01*
X-1140190Y-154530D01*
X-1140365Y-154280D01*
X-1140610Y-154080D01*
X-1140855Y-154030D01*
X-1141100Y-154080D01*
X-1141415Y-154280D01*
X-1141310Y-152980D01*
X-1140365D01*
G01X-1122115Y-185500D02*
Y-182500D01*
X-1120785D01*
G01X-1121275Y-183950D02*
X-1122115D01*
G01X-1118370Y-183900D02*
X-1118230Y-183750D01*
X-1118125Y-183500D01*
X-1118055Y-183150D01*
X-1118125Y-182850D01*
X-1118265Y-182650D01*
X-1118510Y-182500D01*
X-1119455D01*
Y-185500D01*
X-1118300D01*
X-1118055Y-185300D01*
X-1117915Y-185000D01*
X-1117845Y-184650D01*
X-1117915Y-184300D01*
X-1118125Y-184000D01*
X-1118370Y-183900D01*
X-1119455D01*
G01X-1115850Y-185500D02*
Y-182500D01*
X-1116270Y-183100D01*
G01Y-185500D02*
X-1115430D01*
G01X-1132465D02*
Y-182500D01*
X-1131135D01*
G01X-1131625Y-183950D02*
X-1132465D01*
G01X-1129735Y-185100D02*
X-1129455Y-185350D01*
X-1129140Y-185500D01*
X-1128860D01*
X-1128580Y-185350D01*
X-1128370Y-185100D01*
X-1128265Y-184750D01*
X-1128335Y-184400D01*
X-1128510Y-184100D01*
X-1128825Y-183900D01*
X-1129245Y-183800D01*
X-1129490Y-183600D01*
X-1129595Y-183250D01*
X-1129525Y-182900D01*
X-1129350Y-182650D01*
X-1129105Y-182500D01*
X-1128860D01*
X-1128615Y-182600D01*
X-1128405Y-182850D01*
G01X-1126200Y-185500D02*
Y-182500D01*
X-1126620Y-183100D01*
G01Y-185500D02*
X-1125780D01*
G01X-1129330Y-169450D02*
X-1129540Y-169300D01*
X-1129785Y-169200D01*
X-1130065D01*
X-1130380Y-169350D01*
X-1130625Y-169600D01*
X-1130800Y-169900D01*
X-1130940Y-170400D01*
X-1130975Y-170850D01*
X-1130905Y-171300D01*
X-1130800Y-171600D01*
X-1130590Y-171900D01*
X-1130345Y-172100D01*
X-1130100Y-172200D01*
X-1129855D01*
X-1129610Y-172100D01*
X-1129400Y-171950D01*
X-1129225Y-171750D01*
G01X-1127370Y-172200D02*
X-1127300Y-171550D01*
X-1127195Y-171000D01*
X-1127055Y-170500D01*
X-1126880Y-169950D01*
X-1126600Y-169200D01*
X-1128000D01*
G01X-1129330Y-173650D02*
X-1129540Y-173500D01*
X-1129785Y-173400D01*
X-1130065D01*
X-1130380Y-173550D01*
X-1130625Y-173800D01*
X-1130800Y-174100D01*
X-1130940Y-174600D01*
X-1130975Y-175050D01*
X-1130905Y-175500D01*
X-1130800Y-175800D01*
X-1130590Y-176100D01*
X-1130345Y-176300D01*
X-1130100Y-176400D01*
X-1129855D01*
X-1129610Y-176300D01*
X-1129400Y-176150D01*
X-1129225Y-175950D01*
G01X-1127300Y-176400D02*
X-1127055Y-176350D01*
X-1126775Y-176200D01*
X-1126600Y-175950D01*
X-1126530Y-175600D01*
X-1126600Y-175250D01*
X-1126810Y-174950D01*
X-1127125Y-174800D01*
X-1127475D01*
X-1127685Y-174700D01*
X-1127860Y-174450D01*
X-1127930Y-174100D01*
X-1127825Y-173750D01*
X-1127580Y-173500D01*
X-1127300Y-173400D01*
X-1127020Y-173500D01*
X-1126775Y-173750D01*
X-1126670Y-174100D01*
X-1126740Y-174450D01*
X-1126915Y-174700D01*
X-1127125Y-174800D01*
X-1127475D01*
X-1127790Y-174950D01*
X-1128000Y-175250D01*
X-1128070Y-175600D01*
X-1128000Y-175950D01*
X-1127825Y-176200D01*
X-1127545Y-176350D01*
X-1127300Y-176400D01*
G01X-1133530Y-145760D02*
Y-142760D01*
X-1133950Y-143360D01*
G01Y-145760D02*
X-1133110D01*
G01X-1130730D02*
Y-142760D01*
X-1131150Y-143360D01*
G01Y-145760D02*
X-1130310D01*
G01X-1134500Y-109530D02*
Y-106530D01*
X-1134920Y-107130D01*
G01Y-109530D02*
X-1134080D01*
G01X-1131700Y-106530D02*
X-1131980Y-106630D01*
X-1132190Y-106880D01*
X-1132330Y-107180D01*
X-1132435Y-107580D01*
X-1132470Y-108030D01*
X-1132435Y-108480D01*
X-1132330Y-108880D01*
X-1132190Y-109180D01*
X-1131980Y-109430D01*
X-1131700Y-109530D01*
X-1131420Y-109430D01*
X-1131210Y-109180D01*
X-1131070Y-108880D01*
X-1130965Y-108480D01*
X-1130930Y-108030D01*
X-1130965Y-107580D01*
X-1131070Y-107180D01*
X-1131210Y-106880D01*
X-1131420Y-106630D01*
X-1131700Y-106530D01*
G01X-1112000Y-164000D02*
X-1115000D01*
Y-163125D01*
X-1114850Y-162845D01*
X-1114650Y-162670D01*
X-1114250Y-162600D01*
X-1113850Y-162670D01*
X-1113600Y-162880D01*
X-1113450Y-163125D01*
Y-164000D01*
G01Y-163125D02*
X-1112000Y-162600D01*
G01Y-160500D02*
X-1115000D01*
X-1114400Y-160920D01*
G01X-1112000D02*
Y-160080D01*
G01X-1112600Y-158470D02*
X-1112250Y-158260D01*
X-1112050Y-157980D01*
X-1112000Y-157665D01*
X-1112050Y-157385D01*
X-1112300Y-157105D01*
X-1112600Y-156930D01*
X-1112900Y-156895D01*
X-1113250Y-156965D01*
X-1113500Y-157210D01*
X-1113600Y-157455D01*
Y-157770D01*
G01Y-157455D02*
X-1113750Y-157245D01*
X-1114000Y-157070D01*
X-1114300Y-157000D01*
X-1114600Y-157070D01*
X-1114850Y-157245D01*
X-1115000Y-157560D01*
X-1114950Y-157875D01*
X-1114750Y-158190D01*
G01X-1105500Y-164000D02*
X-1108500D01*
Y-163125D01*
X-1108350Y-162845D01*
X-1108150Y-162670D01*
X-1107750Y-162600D01*
X-1107350Y-162670D01*
X-1107100Y-162880D01*
X-1106950Y-163125D01*
Y-164000D01*
G01Y-163125D02*
X-1105500Y-162600D01*
G01Y-160500D02*
X-1108500D01*
X-1107900Y-160920D01*
G01X-1105500D02*
Y-160080D01*
G01Y-157770D02*
X-1106150Y-157700D01*
X-1106700Y-157595D01*
X-1107200Y-157455D01*
X-1107750Y-157280D01*
X-1108500Y-157000D01*
Y-158400D01*
G01X-1104115Y-185500D02*
Y-182500D01*
X-1102785D01*
G01X-1103275Y-183950D02*
X-1104115D01*
G01X-1100370Y-183900D02*
X-1100230Y-183750D01*
X-1100125Y-183500D01*
X-1100055Y-183150D01*
X-1100125Y-182850D01*
X-1100265Y-182650D01*
X-1100510Y-182500D01*
X-1101455D01*
Y-185500D01*
X-1100300D01*
X-1100055Y-185300D01*
X-1099915Y-185000D01*
X-1099845Y-184650D01*
X-1099915Y-184300D01*
X-1100125Y-184000D01*
X-1100370Y-183900D01*
X-1101455D01*
G01X-1098515Y-183000D02*
X-1098305Y-182700D01*
X-1098060Y-182550D01*
X-1097780Y-182500D01*
X-1097430Y-182600D01*
X-1097185Y-182850D01*
X-1097115Y-183150D01*
X-1097150Y-183450D01*
X-1097290Y-183700D01*
X-1097990Y-184200D01*
X-1098305Y-184550D01*
X-1098515Y-185050D01*
X-1098585Y-185500D01*
X-1097115D01*
G01X-1093465D02*
Y-182500D01*
X-1092135D01*
G01X-1092625Y-183950D02*
X-1093465D01*
G01X-1090735Y-185100D02*
X-1090455Y-185350D01*
X-1090140Y-185500D01*
X-1089860D01*
X-1089580Y-185350D01*
X-1089370Y-185100D01*
X-1089265Y-184750D01*
X-1089335Y-184400D01*
X-1089510Y-184100D01*
X-1089825Y-183900D01*
X-1090245Y-183800D01*
X-1090490Y-183600D01*
X-1090595Y-183250D01*
X-1090525Y-182900D01*
X-1090350Y-182650D01*
X-1090105Y-182500D01*
X-1089860D01*
X-1089615Y-182600D01*
X-1089405Y-182850D01*
G01X-1087865Y-183000D02*
X-1087655Y-182700D01*
X-1087410Y-182550D01*
X-1087130Y-182500D01*
X-1086780Y-182600D01*
X-1086535Y-182850D01*
X-1086465Y-183150D01*
X-1086500Y-183450D01*
X-1086640Y-183700D01*
X-1087340Y-184200D01*
X-1087655Y-184550D01*
X-1087865Y-185050D01*
X-1087935Y-185500D01*
X-1086465D01*
G01X-1092630Y-173750D02*
X-1092840Y-173600D01*
X-1093085Y-173500D01*
X-1093365D01*
X-1093680Y-173650D01*
X-1093925Y-173900D01*
X-1094100Y-174200D01*
X-1094240Y-174700D01*
X-1094275Y-175150D01*
X-1094205Y-175600D01*
X-1094100Y-175900D01*
X-1093890Y-176200D01*
X-1093645Y-176400D01*
X-1093400Y-176500D01*
X-1093155D01*
X-1092910Y-176400D01*
X-1092700Y-176250D01*
X-1092525Y-176050D01*
G01X-1091265Y-175250D02*
X-1091020Y-174900D01*
X-1090810Y-174700D01*
X-1090530Y-174600D01*
X-1090285Y-174700D01*
X-1090110Y-174900D01*
X-1089970Y-175200D01*
X-1089935Y-175550D01*
X-1089970Y-175850D01*
X-1090110Y-176150D01*
X-1090320Y-176400D01*
X-1090565Y-176500D01*
X-1090845Y-176400D01*
X-1091090Y-176100D01*
X-1091230Y-175650D01*
X-1091265Y-175150D01*
X-1091195Y-174500D01*
X-1091090Y-174150D01*
X-1090915Y-173800D01*
X-1090670Y-173550D01*
X-1090425Y-173500D01*
X-1090180Y-173600D01*
X-1090005Y-173850D01*
G01X-1092630Y-169250D02*
X-1092840Y-169100D01*
X-1093085Y-169000D01*
X-1093365D01*
X-1093680Y-169150D01*
X-1093925Y-169400D01*
X-1094100Y-169700D01*
X-1094240Y-170200D01*
X-1094275Y-170650D01*
X-1094205Y-171100D01*
X-1094100Y-171400D01*
X-1093890Y-171700D01*
X-1093645Y-171900D01*
X-1093400Y-172000D01*
X-1093155D01*
X-1092910Y-171900D01*
X-1092700Y-171750D01*
X-1092525Y-171550D01*
G01X-1091370D02*
X-1091160Y-171800D01*
X-1090915Y-171950D01*
X-1090600Y-172000D01*
X-1090285Y-171900D01*
X-1090040Y-171700D01*
X-1089865Y-171350D01*
X-1089830Y-170950D01*
X-1089900Y-170550D01*
X-1090075Y-170300D01*
X-1090320Y-170100D01*
X-1090565Y-170050D01*
X-1090810Y-170100D01*
X-1091125Y-170300D01*
X-1091020Y-169000D01*
X-1090075D01*
G01X-1094735Y-142940D02*
X-1094525Y-142640D01*
X-1094280Y-142490D01*
X-1094000Y-142440D01*
X-1093650Y-142540D01*
X-1093405Y-142790D01*
X-1093335Y-143090D01*
X-1093370Y-143390D01*
X-1093510Y-143640D01*
X-1094210Y-144140D01*
X-1094525Y-144490D01*
X-1094735Y-144990D01*
X-1094805Y-145440D01*
X-1093335D01*
G01X-1091270Y-142440D02*
X-1091550Y-142540D01*
X-1091760Y-142790D01*
X-1091900Y-143090D01*
X-1092005Y-143490D01*
X-1092040Y-143940D01*
X-1092005Y-144390D01*
X-1091900Y-144790D01*
X-1091760Y-145090D01*
X-1091550Y-145340D01*
X-1091270Y-145440D01*
X-1090990Y-145340D01*
X-1090780Y-145090D01*
X-1090640Y-144790D01*
X-1090535Y-144390D01*
X-1090500Y-143940D01*
X-1090535Y-143490D01*
X-1090640Y-143090D01*
X-1090780Y-142790D01*
X-1090990Y-142540D01*
X-1091270Y-142440D01*
G01X-1087810Y-155200D02*
X-1087635Y-155500D01*
X-1087425Y-155700D01*
X-1087180Y-155800D01*
X-1086900Y-155700D01*
X-1086690Y-155500D01*
X-1086480Y-155200D01*
X-1086410Y-154800D01*
Y-152800D01*
G01X-1084975Y-154550D02*
X-1084730Y-154200D01*
X-1084520Y-154000D01*
X-1084240Y-153900D01*
X-1083995Y-154000D01*
X-1083820Y-154200D01*
X-1083680Y-154500D01*
X-1083645Y-154850D01*
X-1083680Y-155150D01*
X-1083820Y-155450D01*
X-1084030Y-155700D01*
X-1084275Y-155800D01*
X-1084555Y-155700D01*
X-1084800Y-155400D01*
X-1084940Y-154950D01*
X-1084975Y-154450D01*
X-1084905Y-153800D01*
X-1084800Y-153450D01*
X-1084625Y-153100D01*
X-1084380Y-152850D01*
X-1084135Y-152800D01*
X-1083890Y-152900D01*
X-1083715Y-153150D01*
G01X-1061340Y-62450D02*
X-1061490Y-62660D01*
X-1061590Y-62905D01*
Y-63185D01*
X-1061440Y-63500D01*
X-1061190Y-63745D01*
X-1060890Y-63920D01*
X-1060390Y-64060D01*
X-1059940Y-64095D01*
X-1059490Y-64025D01*
X-1059190Y-63920D01*
X-1058890Y-63710D01*
X-1058690Y-63465D01*
X-1058590Y-63220D01*
Y-62975D01*
X-1058690Y-62730D01*
X-1058840Y-62520D01*
X-1059040Y-62345D01*
G01X-1061090Y-61085D02*
X-1061390Y-60875D01*
X-1061540Y-60630D01*
X-1061590Y-60350D01*
X-1061490Y-60000D01*
X-1061240Y-59755D01*
X-1060940Y-59685D01*
X-1060640Y-59720D01*
X-1060390Y-59860D01*
X-1059890Y-60560D01*
X-1059540Y-60875D01*
X-1059040Y-61085D01*
X-1058590Y-61155D01*
Y-59685D01*
G01X-1058940Y-58215D02*
X-1058690Y-57970D01*
X-1058590Y-57690D01*
X-1058690Y-57410D01*
X-1058990Y-57165D01*
X-1059440Y-56990D01*
X-1059890Y-56920D01*
X-1060440D01*
X-1060890Y-56990D01*
X-1061290Y-57165D01*
X-1061490Y-57375D01*
X-1061590Y-57620D01*
X-1061490Y-57900D01*
X-1061290Y-58110D01*
X-1060990Y-58250D01*
X-1060590Y-58320D01*
X-1060240Y-58250D01*
X-1059890Y-58075D01*
X-1059690Y-57865D01*
X-1059640Y-57620D01*
X-1059740Y-57340D01*
X-1059990Y-57130D01*
X-1060440Y-56920D01*
G01X-1068115Y-45000D02*
Y-42000D01*
X-1066785D01*
G01X-1067275Y-43450D02*
X-1068115D01*
G01X-1064370Y-43400D02*
X-1064230Y-43250D01*
X-1064125Y-43000D01*
X-1064055Y-42650D01*
X-1064125Y-42350D01*
X-1064265Y-42150D01*
X-1064510Y-42000D01*
X-1065455D01*
Y-45000D01*
X-1064300D01*
X-1064055Y-44800D01*
X-1063915Y-44500D01*
X-1063845Y-44150D01*
X-1063915Y-43800D01*
X-1064125Y-43500D01*
X-1064370Y-43400D01*
X-1065455D01*
G01X-1061850Y-45000D02*
Y-42000D01*
X-1062270Y-42600D01*
G01Y-45000D02*
X-1061430D01*
G01X-1059050Y-42000D02*
X-1059330Y-42100D01*
X-1059540Y-42350D01*
X-1059680Y-42650D01*
X-1059785Y-43050D01*
X-1059820Y-43500D01*
X-1059785Y-43950D01*
X-1059680Y-44350D01*
X-1059540Y-44650D01*
X-1059330Y-44900D01*
X-1059050Y-45000D01*
X-1058770Y-44900D01*
X-1058560Y-44650D01*
X-1058420Y-44350D01*
X-1058315Y-43950D01*
X-1058280Y-43500D01*
X-1058315Y-43050D01*
X-1058420Y-42650D01*
X-1058560Y-42350D01*
X-1058770Y-42100D01*
X-1059050Y-42000D01*
G01X-1069041Y-52880D02*
X-1069191Y-53090D01*
X-1069291Y-53335D01*
Y-53615D01*
X-1069140Y-53930D01*
X-1068891Y-54175D01*
X-1068591Y-54350D01*
X-1068091Y-54490D01*
X-1067641Y-54525D01*
X-1067191Y-54455D01*
X-1066891Y-54350D01*
X-1066590Y-54140D01*
X-1066391Y-53895D01*
X-1066291Y-53650D01*
Y-53405D01*
X-1066391Y-53160D01*
X-1066541Y-52950D01*
X-1066740Y-52775D01*
G01X-1066891Y-51620D02*
X-1066541Y-51410D01*
X-1066341Y-51130D01*
X-1066291Y-50815D01*
X-1066341Y-50535D01*
X-1066590Y-50255D01*
X-1066891Y-50080D01*
X-1067191Y-50045D01*
X-1067540Y-50115D01*
X-1067790Y-50360D01*
X-1067891Y-50605D01*
Y-50920D01*
G01Y-50605D02*
X-1068041Y-50395D01*
X-1068290Y-50220D01*
X-1068591Y-50150D01*
X-1068891Y-50220D01*
X-1069140Y-50395D01*
X-1069291Y-50710D01*
X-1069241Y-51025D01*
X-1069041Y-51340D01*
G01X-1069291Y-48050D02*
X-1069191Y-48330D01*
X-1068941Y-48540D01*
X-1068641Y-48680D01*
X-1068240Y-48785D01*
X-1067790Y-48820D01*
X-1067341Y-48785D01*
X-1066940Y-48680D01*
X-1066640Y-48540D01*
X-1066391Y-48330D01*
X-1066291Y-48050D01*
X-1066391Y-47770D01*
X-1066640Y-47560D01*
X-1066940Y-47420D01*
X-1067341Y-47315D01*
X-1067790Y-47280D01*
X-1068240Y-47315D01*
X-1068641Y-47420D01*
X-1068941Y-47560D01*
X-1069191Y-47770D01*
X-1069291Y-48050D01*
G01X-1067940Y-36660D02*
X-1068090Y-36870D01*
X-1068190Y-37115D01*
Y-37395D01*
X-1068040Y-37710D01*
X-1067790Y-37955D01*
X-1067490Y-38130D01*
X-1066990Y-38270D01*
X-1066540Y-38305D01*
X-1066090Y-38235D01*
X-1065790Y-38130D01*
X-1065490Y-37920D01*
X-1065290Y-37675D01*
X-1065190Y-37430D01*
Y-37185D01*
X-1065290Y-36940D01*
X-1065440Y-36730D01*
X-1065640Y-36555D01*
G01X-1065790Y-35400D02*
X-1065440Y-35190D01*
X-1065240Y-34910D01*
X-1065190Y-34595D01*
X-1065240Y-34315D01*
X-1065490Y-34035D01*
X-1065790Y-33860D01*
X-1066090Y-33825D01*
X-1066440Y-33895D01*
X-1066690Y-34140D01*
X-1066790Y-34385D01*
Y-34700D01*
G01Y-34385D02*
X-1066940Y-34175D01*
X-1067190Y-34000D01*
X-1067490Y-33930D01*
X-1067790Y-34000D01*
X-1068040Y-34175D01*
X-1068190Y-34490D01*
X-1068140Y-34805D01*
X-1067940Y-35120D01*
G01X-1065640Y-32600D02*
X-1065390Y-32390D01*
X-1065240Y-32145D01*
X-1065190Y-31830D01*
X-1065290Y-31515D01*
X-1065490Y-31270D01*
X-1065840Y-31095D01*
X-1066240Y-31060D01*
X-1066640Y-31130D01*
X-1066890Y-31305D01*
X-1067090Y-31550D01*
X-1067140Y-31795D01*
X-1067090Y-32040D01*
X-1066890Y-32355D01*
X-1068190Y-32250D01*
Y-31305D01*
G01X-1057970Y-20970D02*
X-1058120Y-21180D01*
X-1058220Y-21425D01*
Y-21705D01*
X-1058070Y-22020D01*
X-1057820Y-22265D01*
X-1057520Y-22440D01*
X-1057020Y-22580D01*
X-1056570Y-22615D01*
X-1056120Y-22545D01*
X-1055820Y-22440D01*
X-1055520Y-22230D01*
X-1055320Y-21985D01*
X-1055220Y-21740D01*
Y-21495D01*
X-1055320Y-21250D01*
X-1055470Y-21040D01*
X-1055670Y-20865D01*
G01X-1055820Y-19710D02*
X-1055470Y-19500D01*
X-1055270Y-19220D01*
X-1055220Y-18905D01*
X-1055270Y-18625D01*
X-1055520Y-18345D01*
X-1055820Y-18170D01*
X-1056120Y-18135D01*
X-1056470Y-18205D01*
X-1056720Y-18450D01*
X-1056820Y-18695D01*
Y-19010D01*
G01Y-18695D02*
X-1056970Y-18485D01*
X-1057220Y-18310D01*
X-1057520Y-18240D01*
X-1057820Y-18310D01*
X-1058070Y-18485D01*
X-1058220Y-18800D01*
X-1058170Y-19115D01*
X-1057970Y-19430D01*
G01X-1057720Y-16805D02*
X-1058020Y-16595D01*
X-1058170Y-16350D01*
X-1058220Y-16070D01*
X-1058120Y-15720D01*
X-1057870Y-15475D01*
X-1057570Y-15405D01*
X-1057270Y-15440D01*
X-1057020Y-15580D01*
X-1056520Y-16280D01*
X-1056170Y-16595D01*
X-1055670Y-16805D01*
X-1055220Y-16875D01*
Y-15405D01*
G01X-1067940Y-13940D02*
X-1068090Y-14150D01*
X-1068190Y-14395D01*
Y-14675D01*
X-1068040Y-14990D01*
X-1067790Y-15235D01*
X-1067490Y-15410D01*
X-1066990Y-15550D01*
X-1066540Y-15585D01*
X-1066090Y-15515D01*
X-1065790Y-15410D01*
X-1065490Y-15200D01*
X-1065290Y-14955D01*
X-1065190Y-14710D01*
Y-14465D01*
X-1065290Y-14220D01*
X-1065440Y-14010D01*
X-1065640Y-13835D01*
G01X-1065790Y-12680D02*
X-1065440Y-12470D01*
X-1065240Y-12190D01*
X-1065190Y-11875D01*
X-1065240Y-11595D01*
X-1065490Y-11315D01*
X-1065790Y-11140D01*
X-1066090Y-11105D01*
X-1066440Y-11175D01*
X-1066690Y-11420D01*
X-1066790Y-11665D01*
Y-11980D01*
G01Y-11665D02*
X-1066940Y-11455D01*
X-1067190Y-11280D01*
X-1067490Y-11210D01*
X-1067790Y-11280D01*
X-1068040Y-11455D01*
X-1068190Y-11770D01*
X-1068140Y-12085D01*
X-1067940Y-12400D01*
G01X-1066440Y-9775D02*
X-1066790Y-9530D01*
X-1066990Y-9320D01*
X-1067090Y-9040D01*
X-1066990Y-8795D01*
X-1066790Y-8620D01*
X-1066490Y-8480D01*
X-1066140Y-8445D01*
X-1065840Y-8480D01*
X-1065540Y-8620D01*
X-1065290Y-8830D01*
X-1065190Y-9075D01*
X-1065290Y-9355D01*
X-1065590Y-9600D01*
X-1066040Y-9740D01*
X-1066540Y-9775D01*
X-1067190Y-9705D01*
X-1067540Y-9600D01*
X-1067890Y-9425D01*
X-1068140Y-9180D01*
X-1068190Y-8935D01*
X-1068090Y-8690D01*
X-1067840Y-8515D01*
G01X-1055113Y-99156D02*
X-1054938Y-99456D01*
X-1054728Y-99656D01*
X-1054483Y-99756D01*
X-1054203Y-99656D01*
X-1053993Y-99456D01*
X-1053783Y-99156D01*
X-1053713Y-98756D01*
Y-96756D01*
G01X-1051613Y-99756D02*
Y-96756D01*
X-1052033Y-97356D01*
G01Y-99756D02*
X-1051193D01*
G01X-1048813Y-96756D02*
X-1049093Y-96856D01*
X-1049303Y-97106D01*
X-1049443Y-97406D01*
X-1049548Y-97806D01*
X-1049583Y-98256D01*
X-1049548Y-98706D01*
X-1049443Y-99106D01*
X-1049303Y-99406D01*
X-1049093Y-99656D01*
X-1048813Y-99756D01*
X-1048533Y-99656D01*
X-1048323Y-99406D01*
X-1048183Y-99106D01*
X-1048078Y-98706D01*
X-1048043Y-98256D01*
X-1048078Y-97806D01*
X-1048183Y-97406D01*
X-1048323Y-97106D01*
X-1048533Y-96856D01*
X-1048813Y-96756D01*
G01X-1042310Y-54270D02*
Y-51270D01*
X-1041435D01*
X-1041155Y-51420D01*
X-1040980Y-51620D01*
X-1040910Y-52020D01*
X-1040980Y-52420D01*
X-1041190Y-52670D01*
X-1041435Y-52820D01*
X-1042310D01*
G01X-1041435D02*
X-1040910Y-54270D01*
G01X-1038880D02*
X-1038810Y-53620D01*
X-1038705Y-53070D01*
X-1038565Y-52570D01*
X-1038390Y-52020D01*
X-1038110Y-51270D01*
X-1039510D01*
G01X-1035590Y-54270D02*
Y-51270D01*
X-1036885Y-53420D01*
X-1035135D01*
G01X-1051430Y-61910D02*
Y-58910D01*
X-1050520Y-61410D01*
X-1049610Y-58910D01*
Y-61910D01*
G01X-1048455D02*
Y-58910D01*
G01X-1046985D02*
Y-61910D01*
G01Y-60410D02*
X-1048455D01*
G01X-1045690Y-61310D02*
X-1045480Y-61660D01*
X-1045200Y-61860D01*
X-1044885Y-61910D01*
X-1044605Y-61860D01*
X-1044325Y-61610D01*
X-1044150Y-61310D01*
X-1044115Y-61010D01*
X-1044185Y-60660D01*
X-1044430Y-60410D01*
X-1044675Y-60310D01*
X-1044990D01*
G01X-1044675D02*
X-1044465Y-60160D01*
X-1044290Y-59910D01*
X-1044220Y-59610D01*
X-1044290Y-59310D01*
X-1044465Y-59060D01*
X-1044780Y-58910D01*
X-1045095Y-58960D01*
X-1045410Y-59160D01*
G01X-1052120Y-38030D02*
X-1052330Y-37880D01*
X-1052575Y-37780D01*
X-1052855D01*
X-1053170Y-37930D01*
X-1053415Y-38180D01*
X-1053590Y-38480D01*
X-1053730Y-38980D01*
X-1053765Y-39430D01*
X-1053695Y-39880D01*
X-1053590Y-40180D01*
X-1053380Y-40480D01*
X-1053135Y-40680D01*
X-1052890Y-40780D01*
X-1052645D01*
X-1052400Y-40680D01*
X-1052190Y-40530D01*
X-1052015Y-40330D01*
G01X-1050860Y-40180D02*
X-1050650Y-40530D01*
X-1050370Y-40730D01*
X-1050055Y-40780D01*
X-1049775Y-40730D01*
X-1049495Y-40480D01*
X-1049320Y-40180D01*
X-1049285Y-39880D01*
X-1049355Y-39530D01*
X-1049600Y-39280D01*
X-1049845Y-39180D01*
X-1050160D01*
G01X-1049845D02*
X-1049635Y-39030D01*
X-1049460Y-38780D01*
X-1049390Y-38480D01*
X-1049460Y-38180D01*
X-1049635Y-37930D01*
X-1049950Y-37780D01*
X-1050265Y-37830D01*
X-1050580Y-38030D01*
G01X-1047290Y-40780D02*
Y-37780D01*
X-1047710Y-38380D01*
G01Y-40780D02*
X-1046870D01*
G01X-1039100Y-49605D02*
X-1042100D01*
Y-48275D01*
G01X-1040650Y-48765D02*
Y-49605D01*
G01X-1039500Y-46875D02*
X-1039250Y-46595D01*
X-1039100Y-46280D01*
Y-46000D01*
X-1039250Y-45720D01*
X-1039500Y-45510D01*
X-1039850Y-45405D01*
X-1040200Y-45475D01*
X-1040500Y-45650D01*
X-1040700Y-45965D01*
X-1040800Y-46385D01*
X-1041000Y-46630D01*
X-1041350Y-46735D01*
X-1041700Y-46665D01*
X-1041950Y-46490D01*
X-1042100Y-46245D01*
Y-46000D01*
X-1042000Y-45755D01*
X-1041750Y-45545D01*
G01X-1039100Y-43340D02*
X-1042100D01*
X-1041500Y-43760D01*
G01X-1039100D02*
Y-42920D01*
G01X-1042100Y-40540D02*
X-1042000Y-40820D01*
X-1041750Y-41030D01*
X-1041450Y-41170D01*
X-1041050Y-41275D01*
X-1040600Y-41310D01*
X-1040150Y-41275D01*
X-1039750Y-41170D01*
X-1039450Y-41030D01*
X-1039200Y-40820D01*
X-1039100Y-40540D01*
X-1039200Y-40260D01*
X-1039450Y-40050D01*
X-1039750Y-39910D01*
X-1040150Y-39805D01*
X-1040600Y-39770D01*
X-1041050Y-39805D01*
X-1041450Y-39910D01*
X-1041750Y-40050D01*
X-1042000Y-40260D01*
X-1042100Y-40540D01*
G01X-1042115Y-31000D02*
Y-28000D01*
X-1040785D01*
G01X-1041275Y-29450D02*
X-1042115D01*
G01X-1038370Y-29400D02*
X-1038230Y-29250D01*
X-1038125Y-29000D01*
X-1038055Y-28650D01*
X-1038125Y-28350D01*
X-1038265Y-28150D01*
X-1038510Y-28000D01*
X-1039455D01*
Y-31000D01*
X-1038300D01*
X-1038055Y-30800D01*
X-1037915Y-30500D01*
X-1037845Y-30150D01*
X-1037915Y-29800D01*
X-1038125Y-29500D01*
X-1038370Y-29400D01*
X-1039455D01*
G01X-1035850Y-31000D02*
X-1035605Y-30950D01*
X-1035325Y-30800D01*
X-1035150Y-30550D01*
X-1035080Y-30200D01*
X-1035150Y-29850D01*
X-1035360Y-29550D01*
X-1035675Y-29400D01*
X-1036025D01*
X-1036235Y-29300D01*
X-1036410Y-29050D01*
X-1036480Y-28700D01*
X-1036375Y-28350D01*
X-1036130Y-28100D01*
X-1035850Y-28000D01*
X-1035570Y-28100D01*
X-1035325Y-28350D01*
X-1035220Y-28700D01*
X-1035290Y-29050D01*
X-1035465Y-29300D01*
X-1035675Y-29400D01*
X-1036025D01*
X-1036340Y-29550D01*
X-1036550Y-29850D01*
X-1036620Y-30200D01*
X-1036550Y-30550D01*
X-1036375Y-30800D01*
X-1036095Y-30950D01*
X-1035850Y-31000D01*
G01X-1043465Y-25000D02*
Y-22000D01*
X-1042135D01*
G01X-1042625Y-23450D02*
X-1043465D01*
G01X-1040735Y-24600D02*
X-1040455Y-24850D01*
X-1040140Y-25000D01*
X-1039860D01*
X-1039580Y-24850D01*
X-1039370Y-24600D01*
X-1039265Y-24250D01*
X-1039335Y-23900D01*
X-1039510Y-23600D01*
X-1039825Y-23400D01*
X-1040245Y-23300D01*
X-1040490Y-23100D01*
X-1040595Y-22750D01*
X-1040525Y-22400D01*
X-1040350Y-22150D01*
X-1040105Y-22000D01*
X-1039860D01*
X-1039615Y-22100D01*
X-1039405Y-22350D01*
G01X-1037200Y-25000D02*
X-1036955Y-24950D01*
X-1036675Y-24800D01*
X-1036500Y-24550D01*
X-1036430Y-24200D01*
X-1036500Y-23850D01*
X-1036710Y-23550D01*
X-1037025Y-23400D01*
X-1037375D01*
X-1037585Y-23300D01*
X-1037760Y-23050D01*
X-1037830Y-22700D01*
X-1037725Y-22350D01*
X-1037480Y-22100D01*
X-1037200Y-22000D01*
X-1036920Y-22100D01*
X-1036675Y-22350D01*
X-1036570Y-22700D01*
X-1036640Y-23050D01*
X-1036815Y-23300D01*
X-1037025Y-23400D01*
X-1037375D01*
X-1037690Y-23550D01*
X-1037900Y-23850D01*
X-1037970Y-24200D01*
X-1037900Y-24550D01*
X-1037725Y-24800D01*
X-1037445Y-24950D01*
X-1037200Y-25000D01*
G01X-1042000Y-36000D02*
Y-33000D01*
X-1041125D01*
X-1040845Y-33150D01*
X-1040670Y-33350D01*
X-1040600Y-33750D01*
X-1040670Y-34150D01*
X-1040880Y-34400D01*
X-1041125Y-34550D01*
X-1042000D01*
G01X-1041125D02*
X-1040600Y-36000D01*
G01X-1038570D02*
X-1038500Y-35350D01*
X-1038395Y-34800D01*
X-1038255Y-34300D01*
X-1038080Y-33750D01*
X-1037800Y-33000D01*
X-1039200D01*
G01X-1036365Y-33500D02*
X-1036155Y-33200D01*
X-1035910Y-33050D01*
X-1035630Y-33000D01*
X-1035280Y-33100D01*
X-1035035Y-33350D01*
X-1034965Y-33650D01*
X-1035000Y-33950D01*
X-1035140Y-34200D01*
X-1035840Y-34700D01*
X-1036155Y-35050D01*
X-1036365Y-35550D01*
X-1036435Y-36000D01*
X-1034965D01*
G01X-1043115Y-6000D02*
Y-3000D01*
X-1041785D01*
G01X-1042275Y-4450D02*
X-1043115D01*
G01X-1039370Y-4400D02*
X-1039230Y-4250D01*
X-1039125Y-4000D01*
X-1039055Y-3650D01*
X-1039125Y-3350D01*
X-1039265Y-3150D01*
X-1039510Y-3000D01*
X-1040455D01*
Y-6000D01*
X-1039300D01*
X-1039055Y-5800D01*
X-1038915Y-5500D01*
X-1038845Y-5150D01*
X-1038915Y-4800D01*
X-1039125Y-4500D01*
X-1039370Y-4400D01*
X-1040455D01*
G01X-1037445Y-5650D02*
X-1037200Y-5900D01*
X-1036920Y-6000D01*
X-1036640Y-5900D01*
X-1036395Y-5600D01*
X-1036220Y-5150D01*
X-1036150Y-4700D01*
Y-4150D01*
X-1036220Y-3700D01*
X-1036395Y-3300D01*
X-1036605Y-3100D01*
X-1036850Y-3000D01*
X-1037130Y-3100D01*
X-1037340Y-3300D01*
X-1037480Y-3600D01*
X-1037550Y-4000D01*
X-1037480Y-4350D01*
X-1037305Y-4700D01*
X-1037095Y-4900D01*
X-1036850Y-4950D01*
X-1036570Y-4850D01*
X-1036360Y-4600D01*
X-1036150Y-4150D01*
G01X-1042965Y-1500D02*
Y1500D01*
X-1041635D01*
G01X-1042125Y50D02*
X-1042965D01*
G01X-1040235Y-1100D02*
X-1039955Y-1350D01*
X-1039640Y-1500D01*
X-1039360D01*
X-1039080Y-1350D01*
X-1038870Y-1100D01*
X-1038765Y-750D01*
X-1038835Y-400D01*
X-1039010Y-100D01*
X-1039325Y100D01*
X-1039745Y200D01*
X-1039990Y400D01*
X-1040095Y750D01*
X-1040025Y1100D01*
X-1039850Y1350D01*
X-1039605Y1500D01*
X-1039360D01*
X-1039115Y1400D01*
X-1038905Y1150D01*
G01X-1037295Y-1150D02*
X-1037050Y-1400D01*
X-1036770Y-1500D01*
X-1036490Y-1400D01*
X-1036245Y-1100D01*
X-1036070Y-650D01*
X-1036000Y-200D01*
Y350D01*
X-1036070Y800D01*
X-1036245Y1200D01*
X-1036455Y1400D01*
X-1036700Y1500D01*
X-1036980Y1400D01*
X-1037190Y1200D01*
X-1037330Y900D01*
X-1037400Y500D01*
X-1037330Y150D01*
X-1037155Y-200D01*
X-1036945Y-400D01*
X-1036700Y-450D01*
X-1036420Y-350D01*
X-1036210Y-100D01*
X-1036000Y350D01*
G01X-1030502Y-94553D02*
X-1030292Y-94253D01*
X-1030047Y-94103D01*
X-1029767Y-94053D01*
X-1029417Y-94153D01*
X-1029172Y-94403D01*
X-1029102Y-94703D01*
X-1029137Y-95003D01*
X-1029277Y-95253D01*
X-1029977Y-95753D01*
X-1030292Y-96103D01*
X-1030502Y-96603D01*
X-1030572Y-97053D01*
X-1029102D01*
G01X-1027807D02*
Y-94053D01*
X-1027107D01*
X-1026827Y-94203D01*
X-1026617Y-94403D01*
X-1026442Y-94703D01*
X-1026302Y-95053D01*
X-1026267Y-95553D01*
X-1026302Y-96053D01*
X-1026442Y-96403D01*
X-1026617Y-96703D01*
X-1026827Y-96903D01*
X-1027107Y-97053D01*
X-1027807D01*
G01X-1030565Y-83000D02*
X-1030355Y-82700D01*
X-1030110Y-82550D01*
X-1029830Y-82500D01*
X-1029480Y-82600D01*
X-1029235Y-82850D01*
X-1029165Y-83150D01*
X-1029200Y-83450D01*
X-1029340Y-83700D01*
X-1030040Y-84200D01*
X-1030355Y-84550D01*
X-1030565Y-85050D01*
X-1030635Y-85500D01*
X-1029165D01*
G01X-1026330Y-82750D02*
X-1026540Y-82600D01*
X-1026785Y-82500D01*
X-1027065D01*
X-1027380Y-82650D01*
X-1027625Y-82900D01*
X-1027800Y-83200D01*
X-1027940Y-83700D01*
X-1027975Y-84150D01*
X-1027905Y-84600D01*
X-1027800Y-84900D01*
X-1027590Y-85200D01*
X-1027345Y-85400D01*
X-1027100Y-85500D01*
X-1026855D01*
X-1026610Y-85400D01*
X-1026400Y-85250D01*
X-1026225Y-85050D01*
G01X-1030502Y-65025D02*
X-1030292Y-64725D01*
X-1030047Y-64575D01*
X-1029767Y-64525D01*
X-1029417Y-64625D01*
X-1029172Y-64875D01*
X-1029102Y-65175D01*
X-1029137Y-65475D01*
X-1029277Y-65725D01*
X-1029977Y-66225D01*
X-1030292Y-66575D01*
X-1030502Y-67075D01*
X-1030572Y-67525D01*
X-1029102D01*
G01X-1026757Y-65925D02*
X-1026617Y-65775D01*
X-1026512Y-65525D01*
X-1026442Y-65175D01*
X-1026512Y-64875D01*
X-1026652Y-64675D01*
X-1026897Y-64525D01*
X-1027842D01*
Y-67525D01*
X-1026687D01*
X-1026442Y-67325D01*
X-1026302Y-67025D01*
X-1026232Y-66675D01*
X-1026302Y-66325D01*
X-1026512Y-66025D01*
X-1026757Y-65925D01*
X-1027842D01*
G01X-1032065Y-45000D02*
X-1031855Y-44700D01*
X-1031610Y-44550D01*
X-1031330Y-44500D01*
X-1030980Y-44600D01*
X-1030735Y-44850D01*
X-1030665Y-45150D01*
X-1030700Y-45450D01*
X-1030840Y-45700D01*
X-1031540Y-46200D01*
X-1031855Y-46550D01*
X-1032065Y-47050D01*
X-1032135Y-47500D01*
X-1030665D01*
G01X-1029475D02*
X-1028600Y-44500D01*
X-1027725Y-47500D01*
G01X-1028040Y-46450D02*
X-1029160D01*
G01X-1039000Y-12000D02*
Y-9000D01*
X-1038125D01*
X-1037845Y-9150D01*
X-1037670Y-9350D01*
X-1037600Y-9750D01*
X-1037670Y-10150D01*
X-1037880Y-10400D01*
X-1038125Y-10550D01*
X-1039000D01*
G01X-1038125D02*
X-1037600Y-12000D01*
G01X-1035570D02*
X-1035500Y-11350D01*
X-1035395Y-10800D01*
X-1035255Y-10300D01*
X-1035080Y-9750D01*
X-1034800Y-9000D01*
X-1036200D01*
G01X-1033470Y-11400D02*
X-1033260Y-11750D01*
X-1032980Y-11950D01*
X-1032665Y-12000D01*
X-1032385Y-11950D01*
X-1032105Y-11700D01*
X-1031930Y-11400D01*
X-1031895Y-11100D01*
X-1031965Y-10750D01*
X-1032210Y-10500D01*
X-1032455Y-10400D01*
X-1032770D01*
G01X-1032455D02*
X-1032245Y-10250D01*
X-1032070Y-10000D01*
X-1032000Y-9700D01*
X-1032070Y-9400D01*
X-1032245Y-9150D01*
X-1032560Y-9000D01*
X-1032875Y-9050D01*
X-1033190Y-9250D01*
G01X-1036880Y-15020D02*
X-1037090Y-14870D01*
X-1037335Y-14770D01*
X-1037615D01*
X-1037930Y-14920D01*
X-1038175Y-15170D01*
X-1038350Y-15470D01*
X-1038490Y-15970D01*
X-1038525Y-16420D01*
X-1038455Y-16870D01*
X-1038350Y-17170D01*
X-1038140Y-17470D01*
X-1037895Y-17670D01*
X-1037650Y-17770D01*
X-1037405D01*
X-1037160Y-17670D01*
X-1036950Y-17520D01*
X-1036775Y-17320D01*
G01X-1035620Y-17170D02*
X-1035410Y-17520D01*
X-1035130Y-17720D01*
X-1034815Y-17770D01*
X-1034535Y-17720D01*
X-1034255Y-17470D01*
X-1034080Y-17170D01*
X-1034045Y-16870D01*
X-1034115Y-16520D01*
X-1034360Y-16270D01*
X-1034605Y-16170D01*
X-1034920D01*
G01X-1034605D02*
X-1034395Y-16020D01*
X-1034220Y-15770D01*
X-1034150Y-15470D01*
X-1034220Y-15170D01*
X-1034395Y-14920D01*
X-1034710Y-14770D01*
X-1035025Y-14820D01*
X-1035340Y-15020D01*
G01X-1032645Y-17420D02*
X-1032400Y-17670D01*
X-1032120Y-17770D01*
X-1031840Y-17670D01*
X-1031595Y-17370D01*
X-1031420Y-16920D01*
X-1031350Y-16470D01*
Y-15920D01*
X-1031420Y-15470D01*
X-1031595Y-15070D01*
X-1031805Y-14870D01*
X-1032050Y-14770D01*
X-1032330Y-14870D01*
X-1032540Y-15070D01*
X-1032680Y-15370D01*
X-1032750Y-15770D01*
X-1032680Y-16120D01*
X-1032505Y-16470D01*
X-1032295Y-16670D01*
X-1032050Y-16720D01*
X-1031770Y-16620D01*
X-1031560Y-16370D01*
X-1031350Y-15920D01*
G01X-1024153Y-180902D02*
X-1023278Y-177902D01*
X-1022403Y-180902D01*
G01X-1022718Y-179852D02*
X-1023838D01*
G01X-1021143Y-179652D02*
X-1020898Y-179302D01*
X-1020688Y-179102D01*
X-1020408Y-179002D01*
X-1020163Y-179102D01*
X-1019988Y-179302D01*
X-1019848Y-179602D01*
X-1019813Y-179952D01*
X-1019848Y-180252D01*
X-1019988Y-180552D01*
X-1020198Y-180802D01*
X-1020443Y-180902D01*
X-1020723Y-180802D01*
X-1020968Y-180502D01*
X-1021108Y-180052D01*
X-1021143Y-179552D01*
X-1021073Y-178902D01*
X-1020968Y-178552D01*
X-1020793Y-178202D01*
X-1020548Y-177952D01*
X-1020303Y-177902D01*
X-1020058Y-178002D01*
X-1019883Y-178252D01*
G01X-1022578Y-158854D02*
X-1023978D01*
Y-155854D01*
X-1022578D01*
G01X-1023138Y-157304D02*
X-1023978D01*
G01X-1021143Y-157604D02*
X-1020898Y-157254D01*
X-1020688Y-157054D01*
X-1020408Y-156954D01*
X-1020163Y-157054D01*
X-1019988Y-157254D01*
X-1019848Y-157554D01*
X-1019813Y-157904D01*
X-1019848Y-158204D01*
X-1019988Y-158504D01*
X-1020198Y-158754D01*
X-1020443Y-158854D01*
X-1020723Y-158754D01*
X-1020968Y-158454D01*
X-1021108Y-158004D01*
X-1021143Y-157504D01*
X-1021073Y-156854D01*
X-1020968Y-156504D01*
X-1020793Y-156154D01*
X-1020548Y-155904D01*
X-1020303Y-155854D01*
X-1020058Y-155954D01*
X-1019883Y-156204D01*
G01X-1023698Y-133807D02*
X-1022858D01*
G01X-1023278D02*
Y-136807D01*
G01X-1023698D02*
X-1022858D01*
G01X-1021143Y-135557D02*
X-1020898Y-135207D01*
X-1020688Y-135007D01*
X-1020408Y-134907D01*
X-1020163Y-135007D01*
X-1019988Y-135207D01*
X-1019848Y-135507D01*
X-1019813Y-135857D01*
X-1019848Y-136157D01*
X-1019988Y-136457D01*
X-1020198Y-136707D01*
X-1020443Y-136807D01*
X-1020723Y-136707D01*
X-1020968Y-136407D01*
X-1021108Y-135957D01*
X-1021143Y-135457D01*
X-1021073Y-134807D01*
X-1020968Y-134457D01*
X-1020793Y-134107D01*
X-1020548Y-133857D01*
X-1020303Y-133807D01*
X-1020058Y-133907D01*
X-1019883Y-134157D01*
G01X-998303Y-116006D02*
X-998128Y-116306D01*
X-997918Y-116506D01*
X-997673Y-116606D01*
X-997393Y-116506D01*
X-997183Y-116306D01*
X-996973Y-116006D01*
X-996903Y-115606D01*
Y-113606D01*
G01X-994803Y-116606D02*
Y-113606D01*
X-995223Y-114206D01*
G01Y-116606D02*
X-994383D01*
G01X-992003D02*
Y-113606D01*
X-992423Y-114206D01*
G01Y-116606D02*
X-991583D01*
G01X-985193Y-109232D02*
X-985018Y-109532D01*
X-984808Y-109732D01*
X-984563Y-109832D01*
X-984283Y-109732D01*
X-984073Y-109532D01*
X-983863Y-109232D01*
X-983793Y-108832D01*
Y-106832D01*
G01X-981693Y-109832D02*
Y-106832D01*
X-982113Y-107432D01*
G01Y-109832D02*
X-981273D01*
G01X-979558Y-107332D02*
X-979348Y-107032D01*
X-979103Y-106882D01*
X-978823Y-106832D01*
X-978473Y-106932D01*
X-978228Y-107182D01*
X-978158Y-107482D01*
X-978193Y-107782D01*
X-978333Y-108032D01*
X-979033Y-108532D01*
X-979348Y-108882D01*
X-979558Y-109382D01*
X-979628Y-109832D01*
X-978158D01*
G01X-970503Y-179902D02*
X-969628Y-176902D01*
X-968753Y-179902D01*
G01X-969068Y-178852D02*
X-970188D01*
G01X-966828Y-179902D02*
Y-176902D01*
X-967248Y-177502D01*
G01Y-179902D02*
X-966408D01*
G01X-968928Y-157854D02*
X-970328D01*
Y-154854D01*
X-968928D01*
G01X-969488Y-156304D02*
X-970328D01*
G01X-966828Y-157854D02*
Y-154854D01*
X-967248Y-155454D01*
G01Y-157854D02*
X-966408D01*
G01X-970048Y-132807D02*
X-969208D01*
G01X-969628D02*
Y-135807D01*
G01X-970048D02*
X-969208D01*
G01X-966828D02*
Y-132807D01*
X-967248Y-133407D01*
G01Y-135807D02*
X-966408D01*
G01X-941636Y-176725D02*
X-944636D01*
Y-175850D01*
X-944486Y-175570D01*
X-944286Y-175395D01*
X-943886Y-175325D01*
X-943486Y-175395D01*
X-943236Y-175605D01*
X-943086Y-175850D01*
Y-176725D01*
G01Y-175850D02*
X-941636Y-175325D01*
G01Y-173225D02*
X-944636D01*
X-944036Y-173645D01*
G01X-941636D02*
Y-172805D01*
G01X-934849Y-100053D02*
Y-97053D01*
X-935269Y-97653D01*
G01Y-100053D02*
X-934429D01*
G01X-932819D02*
Y-97053D01*
X-932119D01*
X-931839Y-97203D01*
X-931629Y-97403D01*
X-931454Y-97703D01*
X-931314Y-98053D01*
X-931279Y-98553D01*
X-931314Y-99053D01*
X-931454Y-99403D01*
X-931629Y-99703D01*
X-931839Y-99903D01*
X-932119Y-100053D01*
X-932819D01*
G01X-934849Y-70525D02*
Y-67525D01*
X-935269Y-68125D01*
G01Y-70525D02*
X-934429D01*
G01X-931769Y-68925D02*
X-931629Y-68775D01*
X-931524Y-68525D01*
X-931454Y-68175D01*
X-931524Y-67875D01*
X-931664Y-67675D01*
X-931909Y-67525D01*
X-932854D01*
Y-70525D01*
X-931699D01*
X-931454Y-70325D01*
X-931314Y-70025D01*
X-931244Y-69675D01*
X-931314Y-69325D01*
X-931524Y-69025D01*
X-931769Y-68925D01*
X-932854D01*
G01X-934849Y-85289D02*
Y-82289D01*
X-935269Y-82889D01*
G01Y-85289D02*
X-934429D01*
G01X-931279Y-82539D02*
X-931489Y-82389D01*
X-931734Y-82289D01*
X-932014D01*
X-932329Y-82439D01*
X-932574Y-82689D01*
X-932749Y-82989D01*
X-932889Y-83489D01*
X-932924Y-83939D01*
X-932854Y-84389D01*
X-932749Y-84689D01*
X-932539Y-84989D01*
X-932294Y-85189D01*
X-932049Y-85289D01*
X-931804D01*
X-931559Y-85189D01*
X-931349Y-85039D01*
X-931174Y-84839D01*
G01X-934849Y-51824D02*
Y-48824D01*
X-935269Y-49424D01*
G01Y-51824D02*
X-934429D01*
G01X-932924D02*
X-932049Y-48824D01*
X-931174Y-51824D01*
G01X-931489Y-50774D02*
X-932609D01*
G01X-927500Y-560000D02*
Y-600000D01*
G01X-915000Y-440000D02*
Y-480000D01*
G01X-890000D02*
Y-600000D01*
G01X-870000Y-440000D02*
Y-480000D01*
G01X-804080Y-139500D02*
Y-136500D01*
X-805375Y-138650D01*
X-803625D01*
G01X-816230Y-101870D02*
Y-98870D01*
X-817525Y-101020D01*
X-815775D01*
G01X-817930Y-83010D02*
X-817720Y-83360D01*
X-817440Y-83560D01*
X-817125Y-83610D01*
X-816845Y-83560D01*
X-816565Y-83310D01*
X-816390Y-83010D01*
X-816355Y-82710D01*
X-816425Y-82360D01*
X-816670Y-82110D01*
X-816915Y-82010D01*
X-817230D01*
G01X-816915D02*
X-816705Y-81860D01*
X-816530Y-81610D01*
X-816460Y-81310D01*
X-816530Y-81010D01*
X-816705Y-80760D01*
X-817020Y-80610D01*
X-817335Y-80660D01*
X-817650Y-80860D01*
G01X-794170Y-124000D02*
Y-126150D01*
X-794030Y-126600D01*
X-793750Y-126900D01*
X-793400Y-127000D01*
X-793050Y-126900D01*
X-792770Y-126600D01*
X-792630Y-126150D01*
Y-124000D01*
G01X-791370Y-126400D02*
X-791160Y-126750D01*
X-790880Y-126950D01*
X-790565Y-127000D01*
X-790285Y-126950D01*
X-790005Y-126700D01*
X-789830Y-126400D01*
X-789795Y-126100D01*
X-789865Y-125750D01*
X-790110Y-125500D01*
X-790355Y-125400D01*
X-790670D01*
G01X-790355D02*
X-790145Y-125250D01*
X-789970Y-125000D01*
X-789900Y-124700D01*
X-789970Y-124400D01*
X-790145Y-124150D01*
X-790460Y-124000D01*
X-790775Y-124050D01*
X-791090Y-124250D01*
G01X-774205Y-98610D02*
X-773995Y-98310D01*
X-773750Y-98160D01*
X-773470Y-98110D01*
X-773120Y-98210D01*
X-772875Y-98460D01*
X-772805Y-98760D01*
X-772840Y-99060D01*
X-772980Y-99310D01*
X-773680Y-99810D01*
X-773995Y-100160D01*
X-774205Y-100660D01*
X-774275Y-101110D01*
X-772805D01*
G01X-758939Y-180008D02*
X-758064Y-177008D01*
X-757189Y-180008D01*
G01X-757504Y-178958D02*
X-758624D01*
G01X-755264Y-180008D02*
Y-177008D01*
X-755684Y-177608D01*
G01Y-180008D02*
X-754844D01*
G01X-752464Y-177008D02*
X-752744Y-177108D01*
X-752954Y-177358D01*
X-753094Y-177658D01*
X-753199Y-178058D01*
X-753234Y-178508D01*
X-753199Y-178958D01*
X-753094Y-179358D01*
X-752954Y-179658D01*
X-752744Y-179908D01*
X-752464Y-180008D01*
X-752184Y-179908D01*
X-751974Y-179658D01*
X-751834Y-179358D01*
X-751729Y-178958D01*
X-751694Y-178508D01*
X-751729Y-178058D01*
X-751834Y-177658D01*
X-751974Y-177358D01*
X-752184Y-177108D01*
X-752464Y-177008D01*
G01X-757364Y-157961D02*
X-758764D01*
Y-154961D01*
X-757364D01*
G01X-757924Y-156411D02*
X-758764D01*
G01X-755264Y-157961D02*
Y-154961D01*
X-755684Y-155561D01*
G01Y-157961D02*
X-754844D01*
G01X-752464Y-154961D02*
X-752744Y-155061D01*
X-752954Y-155311D01*
X-753094Y-155611D01*
X-753199Y-156011D01*
X-753234Y-156461D01*
X-753199Y-156911D01*
X-753094Y-157311D01*
X-752954Y-157611D01*
X-752744Y-157861D01*
X-752464Y-157961D01*
X-752184Y-157861D01*
X-751974Y-157611D01*
X-751834Y-157311D01*
X-751729Y-156911D01*
X-751694Y-156461D01*
X-751729Y-156011D01*
X-751834Y-155611D01*
X-751974Y-155311D01*
X-752184Y-155061D01*
X-752464Y-154961D01*
G01X-758764Y-129802D02*
X-758589Y-130102D01*
X-758379Y-130302D01*
X-758134Y-130402D01*
X-757854Y-130302D01*
X-757644Y-130102D01*
X-757434Y-129802D01*
X-757364Y-129402D01*
Y-127402D01*
G01X-755264Y-130402D02*
Y-127402D01*
X-755684Y-128002D01*
G01Y-130402D02*
X-754844D01*
G01X-752464Y-127402D02*
X-752744Y-127502D01*
X-752954Y-127752D01*
X-753094Y-128052D01*
X-753199Y-128452D01*
X-753234Y-128902D01*
X-753199Y-129352D01*
X-753094Y-129752D01*
X-752954Y-130052D01*
X-752744Y-130302D01*
X-752464Y-130402D01*
X-752184Y-130302D01*
X-751974Y-130052D01*
X-751834Y-129752D01*
X-751729Y-129352D01*
X-751694Y-128902D01*
X-751729Y-128452D01*
X-751834Y-128052D01*
X-751974Y-127752D01*
X-752184Y-127502D01*
X-752464Y-127402D01*
G01X-758961Y-97724D02*
Y-94724D01*
X-758121D01*
X-757841Y-94874D01*
X-757631Y-95224D01*
X-757561Y-95624D01*
X-757631Y-96024D01*
X-757806Y-96324D01*
X-758121Y-96474D01*
X-758961D01*
G01X-755461Y-97724D02*
Y-94724D01*
X-755881Y-95324D01*
G01Y-97724D02*
X-755041D01*
G01X-752661Y-94724D02*
X-752941Y-94824D01*
X-753151Y-95074D01*
X-753291Y-95374D01*
X-753396Y-95774D01*
X-753431Y-96224D01*
X-753396Y-96674D01*
X-753291Y-97074D01*
X-753151Y-97374D01*
X-752941Y-97624D01*
X-752661Y-97724D01*
X-752381Y-97624D01*
X-752171Y-97374D01*
X-752031Y-97074D01*
X-751926Y-96674D01*
X-751891Y-96224D01*
X-751926Y-95774D01*
X-752031Y-95374D01*
X-752171Y-95074D01*
X-752381Y-94824D01*
X-752661Y-94724D01*
G01X-767500Y-78900D02*
X-767325Y-79200D01*
X-767115Y-79400D01*
X-766870Y-79500D01*
X-766590Y-79400D01*
X-766380Y-79200D01*
X-766170Y-78900D01*
X-766100Y-78500D01*
Y-76500D01*
G01X-764665Y-77000D02*
X-764455Y-76700D01*
X-764210Y-76550D01*
X-763930Y-76500D01*
X-763580Y-76600D01*
X-763335Y-76850D01*
X-763265Y-77150D01*
X-763300Y-77450D01*
X-763440Y-77700D01*
X-764140Y-78200D01*
X-764455Y-78550D01*
X-764665Y-79050D01*
X-764735Y-79500D01*
X-763265D01*
G01X-761270D02*
X-761200Y-78850D01*
X-761095Y-78300D01*
X-760955Y-77800D01*
X-760780Y-77250D01*
X-760500Y-76500D01*
X-761900D01*
G01X-714000Y-80400D02*
X-713825Y-80700D01*
X-713615Y-80900D01*
X-713370Y-81000D01*
X-713090Y-80900D01*
X-712880Y-80700D01*
X-712670Y-80400D01*
X-712600Y-80000D01*
Y-78000D01*
G01X-710500Y-81000D02*
Y-78000D01*
X-710920Y-78600D01*
G01Y-81000D02*
X-710080D01*
G01X-708470Y-80400D02*
X-708260Y-80750D01*
X-707980Y-80950D01*
X-707665Y-81000D01*
X-707385Y-80950D01*
X-707105Y-80700D01*
X-706930Y-80400D01*
X-706895Y-80100D01*
X-706965Y-79750D01*
X-707210Y-79500D01*
X-707455Y-79400D01*
X-707770D01*
G01X-707455D02*
X-707245Y-79250D01*
X-707070Y-79000D01*
X-707000Y-78700D01*
X-707070Y-78400D01*
X-707245Y-78150D01*
X-707560Y-78000D01*
X-707875Y-78050D01*
X-708190Y-78250D01*
G01X-680000Y-480000D02*
Y-440000D01*
G01X-669775Y-179000D02*
X-668900Y-176000D01*
X-668025Y-179000D01*
G01X-668340Y-177950D02*
X-669460D01*
G01X-666100Y-179000D02*
Y-176000D01*
X-666520Y-176600D01*
G01Y-179000D02*
X-665680D01*
G01X-669100Y-129400D02*
X-668925Y-129700D01*
X-668715Y-129900D01*
X-668470Y-130000D01*
X-668190Y-129900D01*
X-667980Y-129700D01*
X-667770Y-129400D01*
X-667700Y-129000D01*
Y-127000D01*
G01X-665600Y-130000D02*
Y-127000D01*
X-666020Y-127600D01*
G01Y-130000D02*
X-665180D01*
G01X-669400Y-102000D02*
X-669680Y-101950D01*
X-669925Y-101750D01*
X-670135Y-101450D01*
X-670275Y-101100D01*
X-670345Y-100700D01*
Y-100300D01*
X-670275Y-99900D01*
X-670135Y-99550D01*
X-669925Y-99250D01*
X-669680Y-99050D01*
X-669400Y-99000D01*
X-669120Y-99050D01*
X-668875Y-99250D01*
X-668665Y-99550D01*
X-668525Y-99900D01*
X-668455Y-100300D01*
Y-100700D01*
X-668525Y-101100D01*
X-668665Y-101450D01*
X-668875Y-101750D01*
X-669120Y-101950D01*
X-669400Y-102000D01*
G01X-666600D02*
Y-99000D01*
X-667020Y-99600D01*
G01Y-102000D02*
X-666180D01*
G01X-656348Y-136950D02*
Y-133950D01*
X-655438Y-136450D01*
X-654528Y-133950D01*
Y-136950D01*
G01X-653373D02*
Y-133950D01*
G01X-651903D02*
Y-136950D01*
G01Y-135450D02*
X-653373D01*
G01X-649418Y-136950D02*
Y-133950D01*
X-650713Y-136100D01*
X-648963D01*
G01X-642040Y-123260D02*
X-645040D01*
Y-122385D01*
X-644890Y-122105D01*
X-644690Y-121930D01*
X-644290Y-121860D01*
X-643890Y-121930D01*
X-643640Y-122140D01*
X-643490Y-122385D01*
Y-123260D01*
G01Y-122385D02*
X-642040Y-121860D01*
G01Y-119760D02*
X-642090Y-119515D01*
X-642240Y-119235D01*
X-642490Y-119060D01*
X-642840Y-118990D01*
X-643190Y-119060D01*
X-643490Y-119270D01*
X-643640Y-119585D01*
Y-119935D01*
X-643740Y-120145D01*
X-643990Y-120320D01*
X-644340Y-120390D01*
X-644690Y-120285D01*
X-644940Y-120040D01*
X-645040Y-119760D01*
X-644940Y-119480D01*
X-644690Y-119235D01*
X-644340Y-119130D01*
X-643990Y-119200D01*
X-643740Y-119375D01*
X-643640Y-119585D01*
Y-119935D01*
X-643490Y-120250D01*
X-643190Y-120460D01*
X-642840Y-120530D01*
X-642490Y-120460D01*
X-642240Y-120285D01*
X-642090Y-120005D01*
X-642040Y-119760D01*
G01X-643290Y-117625D02*
X-643640Y-117380D01*
X-643840Y-117170D01*
X-643940Y-116890D01*
X-643840Y-116645D01*
X-643640Y-116470D01*
X-643340Y-116330D01*
X-642990Y-116295D01*
X-642690Y-116330D01*
X-642390Y-116470D01*
X-642140Y-116680D01*
X-642040Y-116925D01*
X-642140Y-117205D01*
X-642440Y-117450D01*
X-642890Y-117590D01*
X-643390Y-117625D01*
X-644040Y-117555D01*
X-644390Y-117450D01*
X-644740Y-117275D01*
X-644990Y-117030D01*
X-645040Y-116785D01*
X-644940Y-116540D01*
X-644690Y-116365D01*
G01X-635800Y-75500D02*
Y-72500D01*
X-636220Y-73100D01*
G01Y-75500D02*
X-635380D01*
G01X-633770Y-75050D02*
X-633560Y-75300D01*
X-633315Y-75450D01*
X-633000Y-75500D01*
X-632685Y-75400D01*
X-632440Y-75200D01*
X-632265Y-74850D01*
X-632230Y-74450D01*
X-632300Y-74050D01*
X-632475Y-73800D01*
X-632720Y-73600D01*
X-632965Y-73550D01*
X-633210Y-73600D01*
X-633525Y-73800D01*
X-633420Y-72500D01*
X-632475D01*
G01X-630970Y-74900D02*
X-630760Y-75250D01*
X-630480Y-75450D01*
X-630165Y-75500D01*
X-629885Y-75450D01*
X-629605Y-75200D01*
X-629430Y-74900D01*
X-629395Y-74600D01*
X-629465Y-74250D01*
X-629710Y-74000D01*
X-629955Y-73900D01*
X-630270D01*
G01X-629955D02*
X-629745Y-73750D01*
X-629570Y-73500D01*
X-629500Y-73200D01*
X-629570Y-72900D01*
X-629745Y-72650D01*
X-630060Y-72500D01*
X-630375Y-72550D01*
X-630690Y-72750D01*
G01X-610000Y-55400D02*
X-609825Y-55700D01*
X-609615Y-55900D01*
X-609370Y-56000D01*
X-609090Y-55900D01*
X-608880Y-55700D01*
X-608670Y-55400D01*
X-608600Y-55000D01*
Y-53000D01*
G01X-606500Y-56000D02*
Y-53000D01*
X-606920Y-53600D01*
G01Y-56000D02*
X-606080D01*
G01X-603280D02*
Y-53000D01*
X-604575Y-55150D01*
X-602825D01*
G01X-582000Y-172000D02*
X-581755Y-171950D01*
X-581475Y-171800D01*
X-581300Y-171550D01*
X-581230Y-171200D01*
X-581300Y-170850D01*
X-581510Y-170550D01*
X-581825Y-170400D01*
X-582175D01*
X-582385Y-170300D01*
X-582560Y-170050D01*
X-582630Y-169700D01*
X-582525Y-169350D01*
X-582280Y-169100D01*
X-582000Y-169000D01*
X-581720Y-169100D01*
X-581475Y-169350D01*
X-581370Y-169700D01*
X-581440Y-170050D01*
X-581615Y-170300D01*
X-581825Y-170400D01*
X-582175D01*
X-582490Y-170550D01*
X-582700Y-170850D01*
X-582770Y-171200D01*
X-582700Y-171550D01*
X-582525Y-171800D01*
X-582245Y-171950D01*
X-582000Y-172000D01*
G01X-583914Y-75390D02*
Y-72390D01*
X-584334Y-72990D01*
G01Y-75390D02*
X-583494D01*
G01X-581779Y-74140D02*
X-581534Y-73790D01*
X-581324Y-73590D01*
X-581044Y-73490D01*
X-580799Y-73590D01*
X-580624Y-73790D01*
X-580484Y-74090D01*
X-580449Y-74440D01*
X-580484Y-74740D01*
X-580624Y-75040D01*
X-580834Y-75290D01*
X-581079Y-75390D01*
X-581359Y-75290D01*
X-581604Y-74990D01*
X-581744Y-74540D01*
X-581779Y-74040D01*
X-581709Y-73390D01*
X-581604Y-73040D01*
X-581429Y-72690D01*
X-581184Y-72440D01*
X-580939Y-72390D01*
X-580694Y-72490D01*
X-580519Y-72740D01*
G01X-578314Y-72390D02*
X-578594Y-72490D01*
X-578804Y-72740D01*
X-578944Y-73040D01*
X-579049Y-73440D01*
X-579084Y-73890D01*
X-579049Y-74340D01*
X-578944Y-74740D01*
X-578804Y-75040D01*
X-578594Y-75290D01*
X-578314Y-75390D01*
X-578034Y-75290D01*
X-577824Y-75040D01*
X-577684Y-74740D01*
X-577579Y-74340D01*
X-577544Y-73890D01*
X-577579Y-73440D01*
X-577684Y-73040D01*
X-577824Y-72740D01*
X-578034Y-72490D01*
X-578314Y-72390D01*
G01X-537250Y-135830D02*
X-537400Y-136040D01*
X-537500Y-136285D01*
Y-136565D01*
X-537350Y-136880D01*
X-537100Y-137125D01*
X-536800Y-137300D01*
X-536300Y-137440D01*
X-535850Y-137475D01*
X-535400Y-137405D01*
X-535100Y-137300D01*
X-534800Y-137090D01*
X-534600Y-136845D01*
X-534500Y-136600D01*
Y-136355D01*
X-534600Y-136110D01*
X-534750Y-135900D01*
X-534950Y-135725D01*
G01X-534500Y-133800D02*
X-537500D01*
X-536900Y-134220D01*
G01X-534500D02*
Y-133380D01*
G01Y-130580D02*
X-537500D01*
X-535350Y-131875D01*
Y-130125D01*
G01X-520450Y-136530D02*
X-520600Y-136740D01*
X-520700Y-136985D01*
Y-137265D01*
X-520550Y-137580D01*
X-520300Y-137825D01*
X-520000Y-138000D01*
X-519500Y-138140D01*
X-519050Y-138175D01*
X-518600Y-138105D01*
X-518300Y-138000D01*
X-518000Y-137790D01*
X-517800Y-137545D01*
X-517700Y-137300D01*
Y-137055D01*
X-517800Y-136810D01*
X-517950Y-136600D01*
X-518150Y-136425D01*
G01X-517700Y-134500D02*
X-520700D01*
X-520100Y-134920D01*
G01X-517700D02*
Y-134080D01*
G01X-518950Y-132365D02*
X-519300Y-132120D01*
X-519500Y-131910D01*
X-519600Y-131630D01*
X-519500Y-131385D01*
X-519300Y-131210D01*
X-519000Y-131070D01*
X-518650Y-131035D01*
X-518350Y-131070D01*
X-518050Y-131210D01*
X-517800Y-131420D01*
X-517700Y-131665D01*
X-517800Y-131945D01*
X-518100Y-132190D01*
X-518550Y-132330D01*
X-519050Y-132365D01*
X-519700Y-132295D01*
X-520050Y-132190D01*
X-520400Y-132015D01*
X-520650Y-131770D01*
X-520700Y-131525D01*
X-520600Y-131280D01*
X-520350Y-131105D01*
G01X-490310Y-99156D02*
X-490135Y-99456D01*
X-489925Y-99656D01*
X-489680Y-99756D01*
X-489400Y-99656D01*
X-489190Y-99456D01*
X-488980Y-99156D01*
X-488910Y-98756D01*
Y-96756D01*
G01X-486810Y-99756D02*
Y-96756D01*
X-487230Y-97356D01*
G01Y-99756D02*
X-486390D01*
G01X-484780Y-99306D02*
X-484570Y-99556D01*
X-484325Y-99706D01*
X-484010Y-99756D01*
X-483695Y-99656D01*
X-483450Y-99456D01*
X-483275Y-99106D01*
X-483240Y-98706D01*
X-483310Y-98306D01*
X-483485Y-98056D01*
X-483730Y-97856D01*
X-483975Y-97806D01*
X-484220Y-97856D01*
X-484535Y-98056D01*
X-484430Y-96756D01*
X-483485D01*
G01X-489910Y-22420D02*
X-492910D01*
Y-21545D01*
X-492760Y-21265D01*
X-492560Y-21090D01*
X-492160Y-21020D01*
X-491760Y-21090D01*
X-491510Y-21300D01*
X-491360Y-21545D01*
Y-22420D01*
G01Y-21545D02*
X-489910Y-21020D01*
G01X-490510Y-19690D02*
X-490160Y-19480D01*
X-489960Y-19200D01*
X-489910Y-18885D01*
X-489960Y-18605D01*
X-490210Y-18325D01*
X-490510Y-18150D01*
X-490810Y-18115D01*
X-491160Y-18185D01*
X-491410Y-18430D01*
X-491510Y-18675D01*
Y-18990D01*
G01Y-18675D02*
X-491660Y-18465D01*
X-491910Y-18290D01*
X-492210Y-18220D01*
X-492510Y-18290D01*
X-492760Y-18465D01*
X-492910Y-18780D01*
X-492860Y-19095D01*
X-492660Y-19410D01*
G01X-490260Y-16715D02*
X-490010Y-16470D01*
X-489910Y-16190D01*
X-490010Y-15910D01*
X-490310Y-15665D01*
X-490760Y-15490D01*
X-491210Y-15420D01*
X-491760D01*
X-492210Y-15490D01*
X-492610Y-15665D01*
X-492810Y-15875D01*
X-492910Y-16120D01*
X-492810Y-16400D01*
X-492610Y-16610D01*
X-492310Y-16750D01*
X-491910Y-16820D01*
X-491560Y-16750D01*
X-491210Y-16575D01*
X-491010Y-16365D01*
X-490960Y-16120D01*
X-491060Y-15840D01*
X-491310Y-15630D01*
X-491760Y-15420D01*
G01X-480820Y-15120D02*
X-480520Y-14945D01*
X-480320Y-14735D01*
X-480220Y-14490D01*
X-480320Y-14210D01*
X-480520Y-14000D01*
X-480820Y-13790D01*
X-481220Y-13720D01*
X-483220D01*
G01X-482720Y-12285D02*
X-483020Y-12075D01*
X-483170Y-11830D01*
X-483220Y-11550D01*
X-483120Y-11200D01*
X-482870Y-10955D01*
X-482570Y-10885D01*
X-482270Y-10920D01*
X-482020Y-11060D01*
X-481520Y-11760D01*
X-481170Y-12075D01*
X-480670Y-12285D01*
X-480220Y-12355D01*
Y-10885D01*
G01X-480570Y-9415D02*
X-480320Y-9170D01*
X-480220Y-8890D01*
X-480320Y-8610D01*
X-480620Y-8365D01*
X-481070Y-8190D01*
X-481520Y-8120D01*
X-482070D01*
X-482520Y-8190D01*
X-482920Y-8365D01*
X-483120Y-8575D01*
X-483220Y-8820D01*
X-483120Y-9100D01*
X-482920Y-9310D01*
X-482620Y-9450D01*
X-482220Y-9520D01*
X-481870Y-9450D01*
X-481520Y-9275D01*
X-481320Y-9065D01*
X-481270Y-8820D01*
X-481370Y-8540D01*
X-481620Y-8330D01*
X-482070Y-8120D01*
G01X-467100Y-160276D02*
Y-157276D01*
X-468395Y-159426D01*
X-466645D01*
G01X-455250Y-97030D02*
X-455400Y-97240D01*
X-455500Y-97485D01*
Y-97765D01*
X-455350Y-98080D01*
X-455100Y-98325D01*
X-454800Y-98500D01*
X-454300Y-98640D01*
X-453850Y-98675D01*
X-453400Y-98605D01*
X-453100Y-98500D01*
X-452800Y-98290D01*
X-452600Y-98045D01*
X-452500Y-97800D01*
Y-97555D01*
X-452600Y-97310D01*
X-452750Y-97100D01*
X-452950Y-96925D01*
G01X-452500Y-95000D02*
X-455500D01*
X-454900Y-95420D01*
G01X-452500D02*
Y-94580D01*
G01X-452950Y-92970D02*
X-452700Y-92760D01*
X-452550Y-92515D01*
X-452500Y-92200D01*
X-452600Y-91885D01*
X-452800Y-91640D01*
X-453150Y-91465D01*
X-453550Y-91430D01*
X-453950Y-91500D01*
X-454200Y-91675D01*
X-454400Y-91920D01*
X-454450Y-92165D01*
X-454400Y-92410D01*
X-454200Y-92725D01*
X-455500Y-92620D01*
Y-91675D01*
G01X-449750Y-97530D02*
X-449900Y-97740D01*
X-450000Y-97985D01*
Y-98265D01*
X-449850Y-98580D01*
X-449600Y-98825D01*
X-449300Y-99000D01*
X-448800Y-99140D01*
X-448350Y-99175D01*
X-447900Y-99105D01*
X-447600Y-99000D01*
X-447300Y-98790D01*
X-447100Y-98545D01*
X-447000Y-98300D01*
Y-98055D01*
X-447100Y-97810D01*
X-447250Y-97600D01*
X-447450Y-97425D01*
G01X-447000Y-95500D02*
X-450000D01*
X-449400Y-95920D01*
G01X-447000D02*
Y-95080D01*
G01X-447600Y-93470D02*
X-447250Y-93260D01*
X-447050Y-92980D01*
X-447000Y-92665D01*
X-447050Y-92385D01*
X-447300Y-92105D01*
X-447600Y-91930D01*
X-447900Y-91895D01*
X-448250Y-91965D01*
X-448500Y-92210D01*
X-448600Y-92455D01*
Y-92770D01*
G01Y-92455D02*
X-448750Y-92245D01*
X-449000Y-92070D01*
X-449300Y-92000D01*
X-449600Y-92070D01*
X-449850Y-92245D01*
X-450000Y-92560D01*
X-449950Y-92875D01*
X-449750Y-93190D01*
G01X-447500Y-58500D02*
X-450500D01*
Y-57625D01*
X-450350Y-57345D01*
X-450150Y-57170D01*
X-449750Y-57100D01*
X-449350Y-57170D01*
X-449100Y-57380D01*
X-448950Y-57625D01*
Y-58500D01*
G01Y-57625D02*
X-447500Y-57100D01*
G01Y-55070D02*
X-448150Y-55000D01*
X-448700Y-54895D01*
X-449200Y-54755D01*
X-449750Y-54580D01*
X-450500Y-54300D01*
Y-55700D01*
G01Y-52200D02*
X-450400Y-52480D01*
X-450150Y-52690D01*
X-449850Y-52830D01*
X-449450Y-52935D01*
X-449000Y-52970D01*
X-448550Y-52935D01*
X-448150Y-52830D01*
X-447850Y-52690D01*
X-447600Y-52480D01*
X-447500Y-52200D01*
X-447600Y-51920D01*
X-447850Y-51710D01*
X-448150Y-51570D01*
X-448550Y-51465D01*
X-449000Y-51430D01*
X-449450Y-51465D01*
X-449850Y-51570D01*
X-450150Y-51710D01*
X-450400Y-51920D01*
X-450500Y-52200D01*
G01X-448500Y-30160D02*
X-451500D01*
Y-29285D01*
X-451350Y-29005D01*
X-451150Y-28830D01*
X-450750Y-28760D01*
X-450350Y-28830D01*
X-450100Y-29040D01*
X-449950Y-29285D01*
Y-30160D01*
G01Y-29285D02*
X-448500Y-28760D01*
G01X-449100Y-27430D02*
X-448750Y-27220D01*
X-448550Y-26940D01*
X-448500Y-26625D01*
X-448550Y-26345D01*
X-448800Y-26065D01*
X-449100Y-25890D01*
X-449400Y-25855D01*
X-449750Y-25925D01*
X-450000Y-26170D01*
X-450100Y-26415D01*
Y-26730D01*
G01Y-26415D02*
X-450250Y-26205D01*
X-450500Y-26030D01*
X-450800Y-25960D01*
X-451100Y-26030D01*
X-451350Y-26205D01*
X-451500Y-26520D01*
X-451450Y-26835D01*
X-451250Y-27150D01*
G01X-448500Y-23930D02*
X-449150Y-23860D01*
X-449700Y-23755D01*
X-450200Y-23615D01*
X-450750Y-23440D01*
X-451500Y-23160D01*
Y-24560D01*
G01X-437500Y-102900D02*
X-437325Y-103200D01*
X-437115Y-103400D01*
X-436870Y-103500D01*
X-436590Y-103400D01*
X-436380Y-103200D01*
X-436170Y-102900D01*
X-436100Y-102500D01*
Y-100500D01*
G01X-434000Y-103500D02*
Y-100500D01*
X-434420Y-101100D01*
G01Y-103500D02*
X-433580D01*
G01X-431865Y-102250D02*
X-431620Y-101900D01*
X-431410Y-101700D01*
X-431130Y-101600D01*
X-430885Y-101700D01*
X-430710Y-101900D01*
X-430570Y-102200D01*
X-430535Y-102550D01*
X-430570Y-102850D01*
X-430710Y-103150D01*
X-430920Y-103400D01*
X-431165Y-103500D01*
X-431445Y-103400D01*
X-431690Y-103100D01*
X-431830Y-102650D01*
X-431865Y-102150D01*
X-431795Y-101500D01*
X-431690Y-101150D01*
X-431515Y-100800D01*
X-431270Y-100550D01*
X-431025Y-100500D01*
X-430780Y-100600D01*
X-430605Y-100850D01*
G01X-430000Y-70000D02*
Y-67000D01*
X-429125D01*
X-428845Y-67150D01*
X-428670Y-67350D01*
X-428600Y-67750D01*
X-428670Y-68150D01*
X-428880Y-68400D01*
X-429125Y-68550D01*
X-430000D01*
G01X-429125D02*
X-428600Y-70000D01*
G01X-427165Y-68750D02*
X-426920Y-68400D01*
X-426710Y-68200D01*
X-426430Y-68100D01*
X-426185Y-68200D01*
X-426010Y-68400D01*
X-425870Y-68700D01*
X-425835Y-69050D01*
X-425870Y-69350D01*
X-426010Y-69650D01*
X-426220Y-69900D01*
X-426465Y-70000D01*
X-426745Y-69900D01*
X-426990Y-69600D01*
X-427130Y-69150D01*
X-427165Y-68650D01*
X-427095Y-68000D01*
X-426990Y-67650D01*
X-426815Y-67300D01*
X-426570Y-67050D01*
X-426325Y-67000D01*
X-426080Y-67100D01*
X-425905Y-67350D01*
G01X-423700Y-70000D02*
Y-67000D01*
X-424120Y-67600D01*
G01Y-70000D02*
X-423280D01*
G01X-430000Y-75500D02*
Y-72500D01*
X-429125D01*
X-428845Y-72650D01*
X-428670Y-72850D01*
X-428600Y-73250D01*
X-428670Y-73650D01*
X-428880Y-73900D01*
X-429125Y-74050D01*
X-430000D01*
G01X-429125D02*
X-428600Y-75500D01*
G01X-427270Y-74900D02*
X-427060Y-75250D01*
X-426780Y-75450D01*
X-426465Y-75500D01*
X-426185Y-75450D01*
X-425905Y-75200D01*
X-425730Y-74900D01*
X-425695Y-74600D01*
X-425765Y-74250D01*
X-426010Y-74000D01*
X-426255Y-73900D01*
X-426570D01*
G01X-426255D02*
X-426045Y-73750D01*
X-425870Y-73500D01*
X-425800Y-73200D01*
X-425870Y-72900D01*
X-426045Y-72650D01*
X-426360Y-72500D01*
X-426675Y-72550D01*
X-426990Y-72750D01*
G01X-423280Y-75500D02*
Y-72500D01*
X-424575Y-74650D01*
X-422825D01*
G01X-427500Y-64500D02*
Y-61500D01*
X-426625D01*
X-426345Y-61650D01*
X-426170Y-61850D01*
X-426100Y-62250D01*
X-426170Y-62650D01*
X-426380Y-62900D01*
X-426625Y-63050D01*
X-427500D01*
G01X-426625D02*
X-426100Y-64500D01*
G01X-424665Y-63250D02*
X-424420Y-62900D01*
X-424210Y-62700D01*
X-423930Y-62600D01*
X-423685Y-62700D01*
X-423510Y-62900D01*
X-423370Y-63200D01*
X-423335Y-63550D01*
X-423370Y-63850D01*
X-423510Y-64150D01*
X-423720Y-64400D01*
X-423965Y-64500D01*
X-424245Y-64400D01*
X-424490Y-64100D01*
X-424630Y-63650D01*
X-424665Y-63150D01*
X-424595Y-62500D01*
X-424490Y-62150D01*
X-424315Y-61800D01*
X-424070Y-61550D01*
X-423825Y-61500D01*
X-423580Y-61600D01*
X-423405Y-61850D01*
G01X-421270Y-64500D02*
X-421200Y-63850D01*
X-421095Y-63300D01*
X-420955Y-62800D01*
X-420780Y-62250D01*
X-420500Y-61500D01*
X-421900D01*
G01X-429500Y-48000D02*
Y-45000D01*
X-428625D01*
X-428345Y-45150D01*
X-428170Y-45350D01*
X-428100Y-45750D01*
X-428170Y-46150D01*
X-428380Y-46400D01*
X-428625Y-46550D01*
X-429500D01*
G01X-428625D02*
X-428100Y-48000D01*
G01X-426665Y-46750D02*
X-426420Y-46400D01*
X-426210Y-46200D01*
X-425930Y-46100D01*
X-425685Y-46200D01*
X-425510Y-46400D01*
X-425370Y-46700D01*
X-425335Y-47050D01*
X-425370Y-47350D01*
X-425510Y-47650D01*
X-425720Y-47900D01*
X-425965Y-48000D01*
X-426245Y-47900D01*
X-426490Y-47600D01*
X-426630Y-47150D01*
X-426665Y-46650D01*
X-426595Y-46000D01*
X-426490Y-45650D01*
X-426315Y-45300D01*
X-426070Y-45050D01*
X-425825Y-45000D01*
X-425580Y-45100D01*
X-425405Y-45350D01*
G01X-423970Y-47550D02*
X-423760Y-47800D01*
X-423515Y-47950D01*
X-423200Y-48000D01*
X-422885Y-47900D01*
X-422640Y-47700D01*
X-422465Y-47350D01*
X-422430Y-46950D01*
X-422500Y-46550D01*
X-422675Y-46300D01*
X-422920Y-46100D01*
X-423165Y-46050D01*
X-423410Y-46100D01*
X-423725Y-46300D01*
X-423620Y-45000D01*
X-422675D01*
G01X-428000Y-53500D02*
Y-50500D01*
X-427125D01*
X-426845Y-50650D01*
X-426670Y-50850D01*
X-426600Y-51250D01*
X-426670Y-51650D01*
X-426880Y-51900D01*
X-427125Y-52050D01*
X-428000D01*
G01X-427125D02*
X-426600Y-53500D01*
G01X-425165Y-52250D02*
X-424920Y-51900D01*
X-424710Y-51700D01*
X-424430Y-51600D01*
X-424185Y-51700D01*
X-424010Y-51900D01*
X-423870Y-52200D01*
X-423835Y-52550D01*
X-423870Y-52850D01*
X-424010Y-53150D01*
X-424220Y-53400D01*
X-424465Y-53500D01*
X-424745Y-53400D01*
X-424990Y-53100D01*
X-425130Y-52650D01*
X-425165Y-52150D01*
X-425095Y-51500D01*
X-424990Y-51150D01*
X-424815Y-50800D01*
X-424570Y-50550D01*
X-424325Y-50500D01*
X-424080Y-50600D01*
X-423905Y-50850D01*
G01X-421280Y-53500D02*
Y-50500D01*
X-422575Y-52650D01*
X-420825D01*
G01X-427500Y-42500D02*
Y-39500D01*
X-426625D01*
X-426345Y-39650D01*
X-426170Y-39850D01*
X-426100Y-40250D01*
X-426170Y-40650D01*
X-426380Y-40900D01*
X-426625Y-41050D01*
X-427500D01*
G01X-426625D02*
X-426100Y-42500D01*
G01X-424665Y-41250D02*
X-424420Y-40900D01*
X-424210Y-40700D01*
X-423930Y-40600D01*
X-423685Y-40700D01*
X-423510Y-40900D01*
X-423370Y-41200D01*
X-423335Y-41550D01*
X-423370Y-41850D01*
X-423510Y-42150D01*
X-423720Y-42400D01*
X-423965Y-42500D01*
X-424245Y-42400D01*
X-424490Y-42100D01*
X-424630Y-41650D01*
X-424665Y-41150D01*
X-424595Y-40500D01*
X-424490Y-40150D01*
X-424315Y-39800D01*
X-424070Y-39550D01*
X-423825Y-39500D01*
X-423580Y-39600D01*
X-423405Y-39850D01*
G01X-421795Y-42150D02*
X-421550Y-42400D01*
X-421270Y-42500D01*
X-420990Y-42400D01*
X-420745Y-42100D01*
X-420570Y-41650D01*
X-420500Y-41200D01*
Y-40650D01*
X-420570Y-40200D01*
X-420745Y-39800D01*
X-420955Y-39600D01*
X-421200Y-39500D01*
X-421480Y-39600D01*
X-421690Y-39800D01*
X-421830Y-40100D01*
X-421900Y-40500D01*
X-421830Y-40850D01*
X-421655Y-41200D01*
X-421445Y-41400D01*
X-421200Y-41450D01*
X-420920Y-41350D01*
X-420710Y-41100D01*
X-420500Y-40650D01*
G01X-428500Y-37000D02*
Y-34000D01*
X-427625D01*
X-427345Y-34150D01*
X-427170Y-34350D01*
X-427100Y-34750D01*
X-427170Y-35150D01*
X-427380Y-35400D01*
X-427625Y-35550D01*
X-428500D01*
G01X-427625D02*
X-427100Y-37000D01*
G01X-425665Y-35750D02*
X-425420Y-35400D01*
X-425210Y-35200D01*
X-424930Y-35100D01*
X-424685Y-35200D01*
X-424510Y-35400D01*
X-424370Y-35700D01*
X-424335Y-36050D01*
X-424370Y-36350D01*
X-424510Y-36650D01*
X-424720Y-36900D01*
X-424965Y-37000D01*
X-425245Y-36900D01*
X-425490Y-36600D01*
X-425630Y-36150D01*
X-425665Y-35650D01*
X-425595Y-35000D01*
X-425490Y-34650D01*
X-425315Y-34300D01*
X-425070Y-34050D01*
X-424825Y-34000D01*
X-424580Y-34100D01*
X-424405Y-34350D01*
G01X-422865Y-34500D02*
X-422655Y-34200D01*
X-422410Y-34050D01*
X-422130Y-34000D01*
X-421780Y-34100D01*
X-421535Y-34350D01*
X-421465Y-34650D01*
X-421500Y-34950D01*
X-421640Y-35200D01*
X-422340Y-35700D01*
X-422655Y-36050D01*
X-422865Y-36550D01*
X-422935Y-37000D01*
X-421465D01*
G01X-428910Y-31580D02*
Y-28580D01*
X-428035D01*
X-427755Y-28730D01*
X-427580Y-28930D01*
X-427510Y-29330D01*
X-427580Y-29730D01*
X-427790Y-29980D01*
X-428035Y-30130D01*
X-428910D01*
G01X-428035D02*
X-427510Y-31580D01*
G01X-426075Y-30330D02*
X-425830Y-29980D01*
X-425620Y-29780D01*
X-425340Y-29680D01*
X-425095Y-29780D01*
X-424920Y-29980D01*
X-424780Y-30280D01*
X-424745Y-30630D01*
X-424780Y-30930D01*
X-424920Y-31230D01*
X-425130Y-31480D01*
X-425375Y-31580D01*
X-425655Y-31480D01*
X-425900Y-31180D01*
X-426040Y-30730D01*
X-426075Y-30230D01*
X-426005Y-29580D01*
X-425900Y-29230D01*
X-425725Y-28880D01*
X-425480Y-28630D01*
X-425235Y-28580D01*
X-424990Y-28680D01*
X-424815Y-28930D01*
G01X-423380Y-30980D02*
X-423170Y-31330D01*
X-422890Y-31530D01*
X-422575Y-31580D01*
X-422295Y-31530D01*
X-422015Y-31280D01*
X-421840Y-30980D01*
X-421805Y-30680D01*
X-421875Y-30330D01*
X-422120Y-30080D01*
X-422365Y-29980D01*
X-422680D01*
G01X-422365D02*
X-422155Y-29830D01*
X-421980Y-29580D01*
X-421910Y-29280D01*
X-421980Y-28980D01*
X-422155Y-28730D01*
X-422470Y-28580D01*
X-422785Y-28630D01*
X-423100Y-28830D01*
G01X-412890Y-189150D02*
X-412715Y-189450D01*
X-412505Y-189650D01*
X-412260Y-189750D01*
X-411980Y-189650D01*
X-411770Y-189450D01*
X-411560Y-189150D01*
X-411490Y-188750D01*
Y-186750D01*
G01X-410055Y-187250D02*
X-409845Y-186950D01*
X-409600Y-186800D01*
X-409320Y-186750D01*
X-408970Y-186850D01*
X-408725Y-187100D01*
X-408655Y-187400D01*
X-408690Y-187700D01*
X-408830Y-187950D01*
X-409530Y-188450D01*
X-409845Y-188800D01*
X-410055Y-189300D01*
X-410125Y-189750D01*
X-408655D01*
G01X-406590Y-186750D02*
X-406870Y-186850D01*
X-407080Y-187100D01*
X-407220Y-187400D01*
X-407325Y-187800D01*
X-407360Y-188250D01*
X-407325Y-188700D01*
X-407220Y-189100D01*
X-407080Y-189400D01*
X-406870Y-189650D01*
X-406590Y-189750D01*
X-406310Y-189650D01*
X-406100Y-189400D01*
X-405960Y-189100D01*
X-405855Y-188700D01*
X-405820Y-188250D01*
X-405855Y-187800D01*
X-405960Y-187400D01*
X-406100Y-187100D01*
X-406310Y-186850D01*
X-406590Y-186750D01*
G01X-417109Y-159676D02*
X-416899Y-160026D01*
X-416619Y-160226D01*
X-416304Y-160276D01*
X-416024Y-160226D01*
X-415744Y-159976D01*
X-415569Y-159676D01*
X-415534Y-159376D01*
X-415604Y-159026D01*
X-415849Y-158776D01*
X-416094Y-158676D01*
X-416409D01*
G01X-416094D02*
X-415884Y-158526D01*
X-415709Y-158276D01*
X-415639Y-157976D01*
X-415709Y-157676D01*
X-415884Y-157426D01*
X-416199Y-157276D01*
X-416514Y-157326D01*
X-416829Y-157526D01*
G01X-417165Y-125000D02*
X-416955Y-124700D01*
X-416710Y-124550D01*
X-416430Y-124500D01*
X-416080Y-124600D01*
X-415835Y-124850D01*
X-415765Y-125150D01*
X-415800Y-125450D01*
X-415940Y-125700D01*
X-416640Y-126200D01*
X-416955Y-126550D01*
X-417165Y-127050D01*
X-417235Y-127500D01*
X-415765D01*
G01X-427000Y-80500D02*
Y-77500D01*
X-426125D01*
X-425845Y-77650D01*
X-425670Y-77850D01*
X-425600Y-78250D01*
X-425670Y-78650D01*
X-425880Y-78900D01*
X-426125Y-79050D01*
X-427000D01*
G01X-426125D02*
X-425600Y-80500D01*
G01X-424270Y-79900D02*
X-424060Y-80250D01*
X-423780Y-80450D01*
X-423465Y-80500D01*
X-423185Y-80450D01*
X-422905Y-80200D01*
X-422730Y-79900D01*
X-422695Y-79600D01*
X-422765Y-79250D01*
X-423010Y-79000D01*
X-423255Y-78900D01*
X-423570D01*
G01X-423255D02*
X-423045Y-78750D01*
X-422870Y-78500D01*
X-422800Y-78200D01*
X-422870Y-77900D01*
X-423045Y-77650D01*
X-423360Y-77500D01*
X-423675Y-77550D01*
X-423990Y-77750D01*
G01X-421470Y-80050D02*
X-421260Y-80300D01*
X-421015Y-80450D01*
X-420700Y-80500D01*
X-420385Y-80400D01*
X-420140Y-80200D01*
X-419965Y-79850D01*
X-419930Y-79450D01*
X-420000Y-79050D01*
X-420175Y-78800D01*
X-420420Y-78600D01*
X-420665Y-78550D01*
X-420910Y-78600D01*
X-421225Y-78800D01*
X-421120Y-77500D01*
X-420175D01*
G01X-427000Y-59000D02*
Y-56000D01*
X-426125D01*
X-425845Y-56150D01*
X-425670Y-56350D01*
X-425600Y-56750D01*
X-425670Y-57150D01*
X-425880Y-57400D01*
X-426125Y-57550D01*
X-427000D01*
G01X-426125D02*
X-425600Y-59000D01*
G01X-424165Y-57750D02*
X-423920Y-57400D01*
X-423710Y-57200D01*
X-423430Y-57100D01*
X-423185Y-57200D01*
X-423010Y-57400D01*
X-422870Y-57700D01*
X-422835Y-58050D01*
X-422870Y-58350D01*
X-423010Y-58650D01*
X-423220Y-58900D01*
X-423465Y-59000D01*
X-423745Y-58900D01*
X-423990Y-58600D01*
X-424130Y-58150D01*
X-424165Y-57650D01*
X-424095Y-57000D01*
X-423990Y-56650D01*
X-423815Y-56300D01*
X-423570Y-56050D01*
X-423325Y-56000D01*
X-423080Y-56100D01*
X-422905Y-56350D01*
G01X-420700Y-59000D02*
X-420455Y-58950D01*
X-420175Y-58800D01*
X-420000Y-58550D01*
X-419930Y-58200D01*
X-420000Y-57850D01*
X-420210Y-57550D01*
X-420525Y-57400D01*
X-420875D01*
X-421085Y-57300D01*
X-421260Y-57050D01*
X-421330Y-56700D01*
X-421225Y-56350D01*
X-420980Y-56100D01*
X-420700Y-56000D01*
X-420420Y-56100D01*
X-420175Y-56350D01*
X-420070Y-56700D01*
X-420140Y-57050D01*
X-420315Y-57300D01*
X-420525Y-57400D01*
X-420875D01*
X-421190Y-57550D01*
X-421400Y-57850D01*
X-421470Y-58200D01*
X-421400Y-58550D01*
X-421225Y-58800D01*
X-420945Y-58950D01*
X-420700Y-59000D01*
G01X-418720Y-18100D02*
X-418420Y-17925D01*
X-418220Y-17715D01*
X-418120Y-17470D01*
X-418220Y-17190D01*
X-418420Y-16980D01*
X-418720Y-16770D01*
X-419120Y-16700D01*
X-421120D01*
G01X-420620Y-15265D02*
X-420920Y-15055D01*
X-421070Y-14810D01*
X-421120Y-14530D01*
X-421020Y-14180D01*
X-420770Y-13935D01*
X-420470Y-13865D01*
X-420170Y-13900D01*
X-419920Y-14040D01*
X-419420Y-14740D01*
X-419070Y-15055D01*
X-418570Y-15265D01*
X-418120Y-15335D01*
Y-13865D01*
G01Y-11800D02*
X-418170Y-11555D01*
X-418320Y-11275D01*
X-418570Y-11100D01*
X-418920Y-11030D01*
X-419270Y-11100D01*
X-419570Y-11310D01*
X-419720Y-11625D01*
Y-11975D01*
X-419820Y-12185D01*
X-420070Y-12360D01*
X-420420Y-12430D01*
X-420770Y-12325D01*
X-421020Y-12080D01*
X-421120Y-11800D01*
X-421020Y-11520D01*
X-420770Y-11275D01*
X-420420Y-11170D01*
X-420070Y-11240D01*
X-419820Y-11415D01*
X-419720Y-11625D01*
Y-11975D01*
X-419570Y-12290D01*
X-419270Y-12500D01*
X-418920Y-12570D01*
X-418570Y-12500D01*
X-418320Y-12325D01*
X-418170Y-12045D01*
X-418120Y-11800D01*
G01X-408705Y-168150D02*
X-408495Y-167850D01*
X-408250Y-167700D01*
X-407970Y-167650D01*
X-407620Y-167750D01*
X-407375Y-168000D01*
X-407305Y-168300D01*
X-407340Y-168600D01*
X-407480Y-168850D01*
X-408180Y-169350D01*
X-408495Y-169700D01*
X-408705Y-170200D01*
X-408775Y-170650D01*
X-407305D01*
G01X-405240Y-167650D02*
X-405520Y-167750D01*
X-405730Y-168000D01*
X-405870Y-168300D01*
X-405975Y-168700D01*
X-406010Y-169150D01*
X-405975Y-169600D01*
X-405870Y-170000D01*
X-405730Y-170300D01*
X-405520Y-170550D01*
X-405240Y-170650D01*
X-404960Y-170550D01*
X-404750Y-170300D01*
X-404610Y-170000D01*
X-404505Y-169600D01*
X-404470Y-169150D01*
X-404505Y-168700D01*
X-404610Y-168300D01*
X-404750Y-168000D01*
X-404960Y-167750D01*
X-405240Y-167650D01*
G01X-409300Y-155450D02*
Y-152450D01*
X-409720Y-153050D01*
G01Y-155450D02*
X-408880D01*
G01X-407095Y-155100D02*
X-406850Y-155350D01*
X-406570Y-155450D01*
X-406290Y-155350D01*
X-406045Y-155050D01*
X-405870Y-154600D01*
X-405800Y-154150D01*
Y-153600D01*
X-405870Y-153150D01*
X-406045Y-152750D01*
X-406255Y-152550D01*
X-406500Y-152450D01*
X-406780Y-152550D01*
X-406990Y-152750D01*
X-407130Y-153050D01*
X-407200Y-153450D01*
X-407130Y-153800D01*
X-406955Y-154150D01*
X-406745Y-154350D01*
X-406500Y-154400D01*
X-406220Y-154300D01*
X-406010Y-154050D01*
X-405800Y-153600D01*
G01X-335775Y-180000D02*
X-334900Y-177000D01*
X-334025Y-180000D01*
G01X-334340Y-178950D02*
X-335460D01*
G01X-332765Y-178750D02*
X-332520Y-178400D01*
X-332310Y-178200D01*
X-332030Y-178100D01*
X-331785Y-178200D01*
X-331610Y-178400D01*
X-331470Y-178700D01*
X-331435Y-179050D01*
X-331470Y-179350D01*
X-331610Y-179650D01*
X-331820Y-179900D01*
X-332065Y-180000D01*
X-332345Y-179900D01*
X-332590Y-179600D01*
X-332730Y-179150D01*
X-332765Y-178650D01*
X-332695Y-178000D01*
X-332590Y-177650D01*
X-332415Y-177300D01*
X-332170Y-177050D01*
X-331925Y-177000D01*
X-331680Y-177100D01*
X-331505Y-177350D01*
G01X-343890Y-189150D02*
X-343715Y-189450D01*
X-343505Y-189650D01*
X-343260Y-189750D01*
X-342980Y-189650D01*
X-342770Y-189450D01*
X-342560Y-189150D01*
X-342490Y-188750D01*
Y-186750D01*
G01X-341055Y-187250D02*
X-340845Y-186950D01*
X-340600Y-186800D01*
X-340320Y-186750D01*
X-339970Y-186850D01*
X-339725Y-187100D01*
X-339655Y-187400D01*
X-339690Y-187700D01*
X-339830Y-187950D01*
X-340530Y-188450D01*
X-340845Y-188800D01*
X-341055Y-189300D01*
X-341125Y-189750D01*
X-339655D01*
G01X-337590D02*
Y-186750D01*
X-338010Y-187350D01*
G01Y-189750D02*
X-337170D01*
G01X-334200Y-161000D02*
X-335600D01*
Y-158000D01*
X-334200D01*
G01X-334760Y-159450D02*
X-335600D01*
G01X-332765Y-159750D02*
X-332520Y-159400D01*
X-332310Y-159200D01*
X-332030Y-159100D01*
X-331785Y-159200D01*
X-331610Y-159400D01*
X-331470Y-159700D01*
X-331435Y-160050D01*
X-331470Y-160350D01*
X-331610Y-160650D01*
X-331820Y-160900D01*
X-332065Y-161000D01*
X-332345Y-160900D01*
X-332590Y-160600D01*
X-332730Y-160150D01*
X-332765Y-159650D01*
X-332695Y-159000D01*
X-332590Y-158650D01*
X-332415Y-158300D01*
X-332170Y-158050D01*
X-331925Y-158000D01*
X-331680Y-158100D01*
X-331505Y-158350D01*
G01X-335320Y-132500D02*
X-334480D01*
G01X-334900D02*
Y-135500D01*
G01X-335320D02*
X-334480D01*
G01X-332765Y-134250D02*
X-332520Y-133900D01*
X-332310Y-133700D01*
X-332030Y-133600D01*
X-331785Y-133700D01*
X-331610Y-133900D01*
X-331470Y-134200D01*
X-331435Y-134550D01*
X-331470Y-134850D01*
X-331610Y-135150D01*
X-331820Y-135400D01*
X-332065Y-135500D01*
X-332345Y-135400D01*
X-332590Y-135100D01*
X-332730Y-134650D01*
X-332765Y-134150D01*
X-332695Y-133500D01*
X-332590Y-133150D01*
X-332415Y-132800D01*
X-332170Y-132550D01*
X-331925Y-132500D01*
X-331680Y-132600D01*
X-331505Y-132850D01*
G01X-333500Y-8000D02*
Y-5000D01*
X-332625D01*
X-332345Y-5150D01*
X-332170Y-5350D01*
X-332100Y-5750D01*
X-332170Y-6150D01*
X-332380Y-6400D01*
X-332625Y-6550D01*
X-333500D01*
G01X-332625D02*
X-332100Y-8000D01*
G01X-329580D02*
Y-5000D01*
X-330875Y-7150D01*
X-329125D01*
G01X-327970Y-7400D02*
X-327760Y-7750D01*
X-327480Y-7950D01*
X-327165Y-8000D01*
X-326885Y-7950D01*
X-326605Y-7700D01*
X-326430Y-7400D01*
X-326395Y-7100D01*
X-326465Y-6750D01*
X-326710Y-6500D01*
X-326955Y-6400D01*
X-327270D01*
G01X-326955D02*
X-326745Y-6250D01*
X-326570Y-6000D01*
X-326500Y-5700D01*
X-326570Y-5400D01*
X-326745Y-5150D01*
X-327060Y-5000D01*
X-327375Y-5050D01*
X-327690Y-5250D01*
G01X-331000Y-44000D02*
Y-41000D01*
X-330125D01*
X-329845Y-41150D01*
X-329670Y-41350D01*
X-329600Y-41750D01*
X-329670Y-42150D01*
X-329880Y-42400D01*
X-330125Y-42550D01*
X-331000D01*
G01X-330125D02*
X-329600Y-44000D01*
G01X-327080D02*
Y-41000D01*
X-328375Y-43150D01*
X-326625D01*
G01X-324700Y-41000D02*
X-324980Y-41100D01*
X-325190Y-41350D01*
X-325330Y-41650D01*
X-325435Y-42050D01*
X-325470Y-42500D01*
X-325435Y-42950D01*
X-325330Y-43350D01*
X-325190Y-43650D01*
X-324980Y-43900D01*
X-324700Y-44000D01*
X-324420Y-43900D01*
X-324210Y-43650D01*
X-324070Y-43350D01*
X-323965Y-42950D01*
X-323930Y-42500D01*
X-323965Y-42050D01*
X-324070Y-41650D01*
X-324210Y-41350D01*
X-324420Y-41100D01*
X-324700Y-41000D01*
G01X-330500Y-49000D02*
Y-46000D01*
X-329625D01*
X-329345Y-46150D01*
X-329170Y-46350D01*
X-329100Y-46750D01*
X-329170Y-47150D01*
X-329380Y-47400D01*
X-329625Y-47550D01*
X-330500D01*
G01X-329625D02*
X-329100Y-49000D01*
G01X-327665Y-47750D02*
X-327420Y-47400D01*
X-327210Y-47200D01*
X-326930Y-47100D01*
X-326685Y-47200D01*
X-326510Y-47400D01*
X-326370Y-47700D01*
X-326335Y-48050D01*
X-326370Y-48350D01*
X-326510Y-48650D01*
X-326720Y-48900D01*
X-326965Y-49000D01*
X-327245Y-48900D01*
X-327490Y-48600D01*
X-327630Y-48150D01*
X-327665Y-47650D01*
X-327595Y-47000D01*
X-327490Y-46650D01*
X-327315Y-46300D01*
X-327070Y-46050D01*
X-326825Y-46000D01*
X-326580Y-46100D01*
X-326405Y-46350D01*
G01X-324865Y-47750D02*
X-324620Y-47400D01*
X-324410Y-47200D01*
X-324130Y-47100D01*
X-323885Y-47200D01*
X-323710Y-47400D01*
X-323570Y-47700D01*
X-323535Y-48050D01*
X-323570Y-48350D01*
X-323710Y-48650D01*
X-323920Y-48900D01*
X-324165Y-49000D01*
X-324445Y-48900D01*
X-324690Y-48600D01*
X-324830Y-48150D01*
X-324865Y-47650D01*
X-324795Y-47000D01*
X-324690Y-46650D01*
X-324515Y-46300D01*
X-324270Y-46050D01*
X-324025Y-46000D01*
X-323780Y-46100D01*
X-323605Y-46350D01*
G01X-331000Y-38000D02*
Y-35000D01*
X-330125D01*
X-329845Y-35150D01*
X-329670Y-35350D01*
X-329600Y-35750D01*
X-329670Y-36150D01*
X-329880Y-36400D01*
X-330125Y-36550D01*
X-331000D01*
G01X-330125D02*
X-329600Y-38000D01*
G01X-328270Y-37400D02*
X-328060Y-37750D01*
X-327780Y-37950D01*
X-327465Y-38000D01*
X-327185Y-37950D01*
X-326905Y-37700D01*
X-326730Y-37400D01*
X-326695Y-37100D01*
X-326765Y-36750D01*
X-327010Y-36500D01*
X-327255Y-36400D01*
X-327570D01*
G01X-327255D02*
X-327045Y-36250D01*
X-326870Y-36000D01*
X-326800Y-35700D01*
X-326870Y-35400D01*
X-327045Y-35150D01*
X-327360Y-35000D01*
X-327675Y-35050D01*
X-327990Y-35250D01*
G01X-325470Y-37400D02*
X-325260Y-37750D01*
X-324980Y-37950D01*
X-324665Y-38000D01*
X-324385Y-37950D01*
X-324105Y-37700D01*
X-323930Y-37400D01*
X-323895Y-37100D01*
X-323965Y-36750D01*
X-324210Y-36500D01*
X-324455Y-36400D01*
X-324770D01*
G01X-324455D02*
X-324245Y-36250D01*
X-324070Y-36000D01*
X-324000Y-35700D01*
X-324070Y-35400D01*
X-324245Y-35150D01*
X-324560Y-35000D01*
X-324875Y-35050D01*
X-325190Y-35250D01*
G01X-330500Y-26000D02*
Y-23000D01*
X-329625D01*
X-329345Y-23150D01*
X-329170Y-23350D01*
X-329100Y-23750D01*
X-329170Y-24150D01*
X-329380Y-24400D01*
X-329625Y-24550D01*
X-330500D01*
G01X-329625D02*
X-329100Y-26000D01*
G01X-327770Y-25400D02*
X-327560Y-25750D01*
X-327280Y-25950D01*
X-326965Y-26000D01*
X-326685Y-25950D01*
X-326405Y-25700D01*
X-326230Y-25400D01*
X-326195Y-25100D01*
X-326265Y-24750D01*
X-326510Y-24500D01*
X-326755Y-24400D01*
X-327070D01*
G01X-326755D02*
X-326545Y-24250D01*
X-326370Y-24000D01*
X-326300Y-23700D01*
X-326370Y-23400D01*
X-326545Y-23150D01*
X-326860Y-23000D01*
X-327175Y-23050D01*
X-327490Y-23250D01*
G01X-324200Y-23000D02*
X-324480Y-23100D01*
X-324690Y-23350D01*
X-324830Y-23650D01*
X-324935Y-24050D01*
X-324970Y-24500D01*
X-324935Y-24950D01*
X-324830Y-25350D01*
X-324690Y-25650D01*
X-324480Y-25900D01*
X-324200Y-26000D01*
X-323920Y-25900D01*
X-323710Y-25650D01*
X-323570Y-25350D01*
X-323465Y-24950D01*
X-323430Y-24500D01*
X-323465Y-24050D01*
X-323570Y-23650D01*
X-323710Y-23350D01*
X-323920Y-23100D01*
X-324200Y-23000D01*
G01X-331500Y-32000D02*
Y-29000D01*
X-330625D01*
X-330345Y-29150D01*
X-330170Y-29350D01*
X-330100Y-29750D01*
X-330170Y-30150D01*
X-330380Y-30400D01*
X-330625Y-30550D01*
X-331500D01*
G01X-330625D02*
X-330100Y-32000D01*
G01X-328770Y-31400D02*
X-328560Y-31750D01*
X-328280Y-31950D01*
X-327965Y-32000D01*
X-327685Y-31950D01*
X-327405Y-31700D01*
X-327230Y-31400D01*
X-327195Y-31100D01*
X-327265Y-30750D01*
X-327510Y-30500D01*
X-327755Y-30400D01*
X-328070D01*
G01X-327755D02*
X-327545Y-30250D01*
X-327370Y-30000D01*
X-327300Y-29700D01*
X-327370Y-29400D01*
X-327545Y-29150D01*
X-327860Y-29000D01*
X-328175Y-29050D01*
X-328490Y-29250D01*
G01X-325865Y-29500D02*
X-325655Y-29200D01*
X-325410Y-29050D01*
X-325130Y-29000D01*
X-324780Y-29100D01*
X-324535Y-29350D01*
X-324465Y-29650D01*
X-324500Y-29950D01*
X-324640Y-30200D01*
X-325340Y-30700D01*
X-325655Y-31050D01*
X-325865Y-31550D01*
X-325935Y-32000D01*
X-324465D01*
G01X-330500Y-21000D02*
Y-18000D01*
X-329625D01*
X-329345Y-18150D01*
X-329170Y-18350D01*
X-329100Y-18750D01*
X-329170Y-19150D01*
X-329380Y-19400D01*
X-329625Y-19550D01*
X-330500D01*
G01X-329625D02*
X-329100Y-21000D01*
G01X-327770Y-20400D02*
X-327560Y-20750D01*
X-327280Y-20950D01*
X-326965Y-21000D01*
X-326685Y-20950D01*
X-326405Y-20700D01*
X-326230Y-20400D01*
X-326195Y-20100D01*
X-326265Y-19750D01*
X-326510Y-19500D01*
X-326755Y-19400D01*
X-327070D01*
G01X-326755D02*
X-326545Y-19250D01*
X-326370Y-19000D01*
X-326300Y-18700D01*
X-326370Y-18400D01*
X-326545Y-18150D01*
X-326860Y-18000D01*
X-327175Y-18050D01*
X-327490Y-18250D01*
G01X-324200Y-21000D02*
Y-18000D01*
X-324620Y-18600D01*
G01Y-21000D02*
X-323780D01*
G01X-331500Y-14500D02*
Y-11500D01*
X-330625D01*
X-330345Y-11650D01*
X-330170Y-11850D01*
X-330100Y-12250D01*
X-330170Y-12650D01*
X-330380Y-12900D01*
X-330625Y-13050D01*
X-331500D01*
G01X-330625D02*
X-330100Y-14500D01*
G01X-328770Y-14050D02*
X-328560Y-14300D01*
X-328315Y-14450D01*
X-328000Y-14500D01*
X-327685Y-14400D01*
X-327440Y-14200D01*
X-327265Y-13850D01*
X-327230Y-13450D01*
X-327300Y-13050D01*
X-327475Y-12800D01*
X-327720Y-12600D01*
X-327965Y-12550D01*
X-328210Y-12600D01*
X-328525Y-12800D01*
X-328420Y-11500D01*
X-327475D01*
G01X-325970Y-14050D02*
X-325760Y-14300D01*
X-325515Y-14450D01*
X-325200Y-14500D01*
X-324885Y-14400D01*
X-324640Y-14200D01*
X-324465Y-13850D01*
X-324430Y-13450D01*
X-324500Y-13050D01*
X-324675Y-12800D01*
X-324920Y-12600D01*
X-325165Y-12550D01*
X-325410Y-12600D01*
X-325725Y-12800D01*
X-325620Y-11500D01*
X-324675D01*
G01X-330890Y-2970D02*
Y30D01*
X-330015D01*
X-329735Y-120D01*
X-329560Y-320D01*
X-329490Y-720D01*
X-329560Y-1120D01*
X-329770Y-1370D01*
X-330015Y-1520D01*
X-330890D01*
G01X-330015D02*
X-329490Y-2970D01*
G01X-328160Y-2520D02*
X-327950Y-2770D01*
X-327705Y-2920D01*
X-327390Y-2970D01*
X-327075Y-2870D01*
X-326830Y-2670D01*
X-326655Y-2320D01*
X-326620Y-1920D01*
X-326690Y-1520D01*
X-326865Y-1270D01*
X-327110Y-1070D01*
X-327355Y-1020D01*
X-327600Y-1070D01*
X-327915Y-1270D01*
X-327810Y30D01*
X-326865D01*
G01X-324660Y-2970D02*
X-324590Y-2320D01*
X-324485Y-1770D01*
X-324345Y-1270D01*
X-324170Y-720D01*
X-323890Y30D01*
X-325290D01*
G01X-307500Y-107900D02*
X-307325Y-108200D01*
X-307115Y-108400D01*
X-306870Y-108500D01*
X-306590Y-108400D01*
X-306380Y-108200D01*
X-306170Y-107900D01*
X-306100Y-107500D01*
Y-105500D01*
G01X-304000Y-108500D02*
Y-105500D01*
X-304420Y-106100D01*
G01Y-108500D02*
X-303580D01*
G01X-301795Y-108150D02*
X-301550Y-108400D01*
X-301270Y-108500D01*
X-300990Y-108400D01*
X-300745Y-108100D01*
X-300570Y-107650D01*
X-300500Y-107200D01*
Y-106650D01*
X-300570Y-106200D01*
X-300745Y-105800D01*
X-300955Y-105600D01*
X-301200Y-105500D01*
X-301480Y-105600D01*
X-301690Y-105800D01*
X-301830Y-106100D01*
X-301900Y-106500D01*
X-301830Y-106850D01*
X-301655Y-107200D01*
X-301445Y-107400D01*
X-301200Y-107450D01*
X-300920Y-107350D01*
X-300710Y-107100D01*
X-300500Y-106650D01*
G01X-292775Y-184500D02*
X-291900Y-181500D01*
X-291025Y-184500D01*
G01X-291340Y-183450D02*
X-292460D01*
G01X-289100Y-184500D02*
Y-181500D01*
X-289520Y-182100D01*
G01Y-184500D02*
X-288680D01*
G01X-288500Y-39800D02*
Y-36800D01*
X-287625D01*
X-287345Y-36950D01*
X-287170Y-37150D01*
X-287100Y-37550D01*
X-287170Y-37950D01*
X-287380Y-38200D01*
X-287625Y-38350D01*
X-288500D01*
G01X-287625D02*
X-287100Y-39800D01*
G01X-285770Y-39350D02*
X-285560Y-39600D01*
X-285315Y-39750D01*
X-285000Y-39800D01*
X-284685Y-39700D01*
X-284440Y-39500D01*
X-284265Y-39150D01*
X-284230Y-38750D01*
X-284300Y-38350D01*
X-284475Y-38100D01*
X-284720Y-37900D01*
X-284965Y-37850D01*
X-285210Y-37900D01*
X-285525Y-38100D01*
X-285420Y-36800D01*
X-284475D01*
G01X-282200D02*
X-282480Y-36900D01*
X-282690Y-37150D01*
X-282830Y-37450D01*
X-282935Y-37850D01*
X-282970Y-38300D01*
X-282935Y-38750D01*
X-282830Y-39150D01*
X-282690Y-39450D01*
X-282480Y-39700D01*
X-282200Y-39800D01*
X-281920Y-39700D01*
X-281710Y-39450D01*
X-281570Y-39150D01*
X-281465Y-38750D01*
X-281430Y-38300D01*
X-281465Y-37850D01*
X-281570Y-37450D01*
X-281710Y-37150D01*
X-281920Y-36900D01*
X-282200Y-36800D01*
G01X-290700Y-50300D02*
Y-47300D01*
X-289825D01*
X-289545Y-47450D01*
X-289370Y-47650D01*
X-289300Y-48050D01*
X-289370Y-48450D01*
X-289580Y-48700D01*
X-289825Y-48850D01*
X-290700D01*
G01X-289825D02*
X-289300Y-50300D01*
G01X-287970Y-49850D02*
X-287760Y-50100D01*
X-287515Y-50250D01*
X-287200Y-50300D01*
X-286885Y-50200D01*
X-286640Y-50000D01*
X-286465Y-49650D01*
X-286430Y-49250D01*
X-286500Y-48850D01*
X-286675Y-48600D01*
X-286920Y-48400D01*
X-287165Y-48350D01*
X-287410Y-48400D01*
X-287725Y-48600D01*
X-287620Y-47300D01*
X-286675D01*
G01X-283980Y-50300D02*
Y-47300D01*
X-285275Y-49450D01*
X-283525D01*
G01X-288200Y-44800D02*
Y-41800D01*
X-287325D01*
X-287045Y-41950D01*
X-286870Y-42150D01*
X-286800Y-42550D01*
X-286870Y-42950D01*
X-287080Y-43200D01*
X-287325Y-43350D01*
X-288200D01*
G01X-287325D02*
X-286800Y-44800D01*
G01X-285470Y-44350D02*
X-285260Y-44600D01*
X-285015Y-44750D01*
X-284700Y-44800D01*
X-284385Y-44700D01*
X-284140Y-44500D01*
X-283965Y-44150D01*
X-283930Y-43750D01*
X-284000Y-43350D01*
X-284175Y-43100D01*
X-284420Y-42900D01*
X-284665Y-42850D01*
X-284910Y-42900D01*
X-285225Y-43100D01*
X-285120Y-41800D01*
X-284175D01*
G01X-282565Y-43550D02*
X-282320Y-43200D01*
X-282110Y-43000D01*
X-281830Y-42900D01*
X-281585Y-43000D01*
X-281410Y-43200D01*
X-281270Y-43500D01*
X-281235Y-43850D01*
X-281270Y-44150D01*
X-281410Y-44450D01*
X-281620Y-44700D01*
X-281865Y-44800D01*
X-282145Y-44700D01*
X-282390Y-44400D01*
X-282530Y-43950D01*
X-282565Y-43450D01*
X-282495Y-42800D01*
X-282390Y-42450D01*
X-282215Y-42100D01*
X-281970Y-41850D01*
X-281725Y-41800D01*
X-281480Y-41900D01*
X-281305Y-42150D01*
G01X-287550Y-33800D02*
Y-30800D01*
X-286675D01*
X-286395Y-30950D01*
X-286220Y-31150D01*
X-286150Y-31550D01*
X-286220Y-31950D01*
X-286430Y-32200D01*
X-286675Y-32350D01*
X-287550D01*
G01X-286675D02*
X-286150Y-33800D01*
G01X-284820Y-33350D02*
X-284610Y-33600D01*
X-284365Y-33750D01*
X-284050Y-33800D01*
X-283735Y-33700D01*
X-283490Y-33500D01*
X-283315Y-33150D01*
X-283280Y-32750D01*
X-283350Y-32350D01*
X-283525Y-32100D01*
X-283770Y-31900D01*
X-284015Y-31850D01*
X-284260Y-31900D01*
X-284575Y-32100D01*
X-284470Y-30800D01*
X-283525D01*
G01X-281250Y-33800D02*
Y-30800D01*
X-281670Y-31400D01*
G01Y-33800D02*
X-280830D01*
G01X-288500Y-27500D02*
Y-24500D01*
X-287625D01*
X-287345Y-24650D01*
X-287170Y-24850D01*
X-287100Y-25250D01*
X-287170Y-25650D01*
X-287380Y-25900D01*
X-287625Y-26050D01*
X-288500D01*
G01X-287625D02*
X-287100Y-27500D01*
G01X-284580D02*
Y-24500D01*
X-285875Y-26650D01*
X-284125D01*
G01X-282200Y-27500D02*
X-281955Y-27450D01*
X-281675Y-27300D01*
X-281500Y-27050D01*
X-281430Y-26700D01*
X-281500Y-26350D01*
X-281710Y-26050D01*
X-282025Y-25900D01*
X-282375D01*
X-282585Y-25800D01*
X-282760Y-25550D01*
X-282830Y-25200D01*
X-282725Y-24850D01*
X-282480Y-24600D01*
X-282200Y-24500D01*
X-281920Y-24600D01*
X-281675Y-24850D01*
X-281570Y-25200D01*
X-281640Y-25550D01*
X-281815Y-25800D01*
X-282025Y-25900D01*
X-282375D01*
X-282690Y-26050D01*
X-282900Y-26350D01*
X-282970Y-26700D01*
X-282900Y-27050D01*
X-282725Y-27300D01*
X-282445Y-27450D01*
X-282200Y-27500D01*
G01X-290000Y-22000D02*
Y-19000D01*
X-289125D01*
X-288845Y-19150D01*
X-288670Y-19350D01*
X-288600Y-19750D01*
X-288670Y-20150D01*
X-288880Y-20400D01*
X-289125Y-20550D01*
X-290000D01*
G01X-289125D02*
X-288600Y-22000D01*
G01X-286080D02*
Y-19000D01*
X-287375Y-21150D01*
X-285625D01*
G01X-284295Y-21650D02*
X-284050Y-21900D01*
X-283770Y-22000D01*
X-283490Y-21900D01*
X-283245Y-21600D01*
X-283070Y-21150D01*
X-283000Y-20700D01*
Y-20150D01*
X-283070Y-19700D01*
X-283245Y-19300D01*
X-283455Y-19100D01*
X-283700Y-19000D01*
X-283980Y-19100D01*
X-284190Y-19300D01*
X-284330Y-19600D01*
X-284400Y-20000D01*
X-284330Y-20350D01*
X-284155Y-20700D01*
X-283945Y-20900D01*
X-283700Y-20950D01*
X-283420Y-20850D01*
X-283210Y-20600D01*
X-283000Y-20150D01*
G01X-289000Y-17000D02*
Y-14000D01*
X-288125D01*
X-287845Y-14150D01*
X-287670Y-14350D01*
X-287600Y-14750D01*
X-287670Y-15150D01*
X-287880Y-15400D01*
X-288125Y-15550D01*
X-289000D01*
G01X-288125D02*
X-287600Y-17000D01*
G01X-286270Y-16550D02*
X-286060Y-16800D01*
X-285815Y-16950D01*
X-285500Y-17000D01*
X-285185Y-16900D01*
X-284940Y-16700D01*
X-284765Y-16350D01*
X-284730Y-15950D01*
X-284800Y-15550D01*
X-284975Y-15300D01*
X-285220Y-15100D01*
X-285465Y-15050D01*
X-285710Y-15100D01*
X-286025Y-15300D01*
X-285920Y-14000D01*
X-284975D01*
G01X-283470Y-16400D02*
X-283260Y-16750D01*
X-282980Y-16950D01*
X-282665Y-17000D01*
X-282385Y-16950D01*
X-282105Y-16700D01*
X-281930Y-16400D01*
X-281895Y-16100D01*
X-281965Y-15750D01*
X-282210Y-15500D01*
X-282455Y-15400D01*
X-282770D01*
G01X-282455D02*
X-282245Y-15250D01*
X-282070Y-15000D01*
X-282000Y-14700D01*
X-282070Y-14400D01*
X-282245Y-14150D01*
X-282560Y-14000D01*
X-282875Y-14050D01*
X-283190Y-14250D01*
G01X-288000Y-11000D02*
Y-8000D01*
X-287125D01*
X-286845Y-8150D01*
X-286670Y-8350D01*
X-286600Y-8750D01*
X-286670Y-9150D01*
X-286880Y-9400D01*
X-287125Y-9550D01*
X-288000D01*
G01X-287125D02*
X-286600Y-11000D01*
G01X-285270Y-10550D02*
X-285060Y-10800D01*
X-284815Y-10950D01*
X-284500Y-11000D01*
X-284185Y-10900D01*
X-283940Y-10700D01*
X-283765Y-10350D01*
X-283730Y-9950D01*
X-283800Y-9550D01*
X-283975Y-9300D01*
X-284220Y-9100D01*
X-284465Y-9050D01*
X-284710Y-9100D01*
X-285025Y-9300D01*
X-284920Y-8000D01*
X-283975D01*
G01X-282365Y-8500D02*
X-282155Y-8200D01*
X-281910Y-8050D01*
X-281630Y-8000D01*
X-281280Y-8100D01*
X-281035Y-8350D01*
X-280965Y-8650D01*
X-281000Y-8950D01*
X-281140Y-9200D01*
X-281840Y-9700D01*
X-282155Y-10050D01*
X-282365Y-10550D01*
X-282435Y-11000D01*
X-280965D01*
G01X-288000Y-6000D02*
Y-3000D01*
X-287125D01*
X-286845Y-3150D01*
X-286670Y-3350D01*
X-286600Y-3750D01*
X-286670Y-4150D01*
X-286880Y-4400D01*
X-287125Y-4550D01*
X-288000D01*
G01X-287125D02*
X-286600Y-6000D01*
G01X-284080D02*
Y-3000D01*
X-285375Y-5150D01*
X-283625D01*
G01X-282365Y-4750D02*
X-282120Y-4400D01*
X-281910Y-4200D01*
X-281630Y-4100D01*
X-281385Y-4200D01*
X-281210Y-4400D01*
X-281070Y-4700D01*
X-281035Y-5050D01*
X-281070Y-5350D01*
X-281210Y-5650D01*
X-281420Y-5900D01*
X-281665Y-6000D01*
X-281945Y-5900D01*
X-282190Y-5600D01*
X-282330Y-5150D01*
X-282365Y-4650D01*
X-282295Y-4000D01*
X-282190Y-3650D01*
X-282015Y-3300D01*
X-281770Y-3050D01*
X-281525Y-3000D01*
X-281280Y-3100D01*
X-281105Y-3350D01*
G01X-275080Y-155250D02*
X-274905Y-155550D01*
X-274695Y-155750D01*
X-274450Y-155850D01*
X-274170Y-155750D01*
X-273960Y-155550D01*
X-273750Y-155250D01*
X-273680Y-154850D01*
Y-152850D01*
G01X-271580Y-155850D02*
Y-152850D01*
X-272000Y-153450D01*
G01Y-155850D02*
X-271160D01*
G01X-268850D02*
X-268780Y-155200D01*
X-268675Y-154650D01*
X-268535Y-154150D01*
X-268360Y-153600D01*
X-268080Y-152850D01*
X-269480D01*
G01X-262965Y-185500D02*
Y-182500D01*
X-261635D01*
G01X-262125Y-183950D02*
X-262965D01*
G01X-260235Y-185100D02*
X-259955Y-185350D01*
X-259640Y-185500D01*
X-259360D01*
X-259080Y-185350D01*
X-258870Y-185100D01*
X-258765Y-184750D01*
X-258835Y-184400D01*
X-259010Y-184100D01*
X-259325Y-183900D01*
X-259745Y-183800D01*
X-259990Y-183600D01*
X-260095Y-183250D01*
X-260025Y-182900D01*
X-259850Y-182650D01*
X-259605Y-182500D01*
X-259360D01*
X-259115Y-182600D01*
X-258905Y-182850D01*
G01X-257470Y-184900D02*
X-257260Y-185250D01*
X-256980Y-185450D01*
X-256665Y-185500D01*
X-256385Y-185450D01*
X-256105Y-185200D01*
X-255930Y-184900D01*
X-255895Y-184600D01*
X-255965Y-184250D01*
X-256210Y-184000D01*
X-256455Y-183900D01*
X-256770D01*
G01X-256455D02*
X-256245Y-183750D01*
X-256070Y-183500D01*
X-256000Y-183200D01*
X-256070Y-182900D01*
X-256245Y-182650D01*
X-256560Y-182500D01*
X-256875Y-182550D01*
X-257190Y-182750D01*
G01X-262530Y-169250D02*
X-262740Y-169100D01*
X-262985Y-169000D01*
X-263265D01*
X-263580Y-169150D01*
X-263825Y-169400D01*
X-264000Y-169700D01*
X-264140Y-170200D01*
X-264175Y-170650D01*
X-264105Y-171100D01*
X-264000Y-171400D01*
X-263790Y-171700D01*
X-263545Y-171900D01*
X-263300Y-172000D01*
X-263055D01*
X-262810Y-171900D01*
X-262600Y-171750D01*
X-262425Y-171550D01*
G01X-260500Y-172000D02*
Y-169000D01*
X-260920Y-169600D01*
G01Y-172000D02*
X-260080D01*
G01X-257700D02*
Y-169000D01*
X-258120Y-169600D01*
G01Y-172000D02*
X-257280D01*
G01X-262530Y-174250D02*
X-262740Y-174100D01*
X-262985Y-174000D01*
X-263265D01*
X-263580Y-174150D01*
X-263825Y-174400D01*
X-264000Y-174700D01*
X-264140Y-175200D01*
X-264175Y-175650D01*
X-264105Y-176100D01*
X-264000Y-176400D01*
X-263790Y-176700D01*
X-263545Y-176900D01*
X-263300Y-177000D01*
X-263055D01*
X-262810Y-176900D01*
X-262600Y-176750D01*
X-262425Y-176550D01*
G01X-260500Y-177000D02*
Y-174000D01*
X-260920Y-174600D01*
G01Y-177000D02*
X-260080D01*
G01X-258365Y-174500D02*
X-258155Y-174200D01*
X-257910Y-174050D01*
X-257630Y-174000D01*
X-257280Y-174100D01*
X-257035Y-174350D01*
X-256965Y-174650D01*
X-257000Y-174950D01*
X-257140Y-175200D01*
X-257840Y-175700D01*
X-258155Y-176050D01*
X-258365Y-176550D01*
X-258435Y-177000D01*
X-256965D01*
G01X-263690Y-145640D02*
Y-142640D01*
X-264110Y-143240D01*
G01Y-145640D02*
X-263270D01*
G01X-260890D02*
Y-142640D01*
X-261310Y-143240D01*
G01Y-145640D02*
X-260470D01*
G01X-264070Y-109360D02*
Y-106360D01*
X-264490Y-106960D01*
G01Y-109360D02*
X-263650D01*
G01X-261270Y-106360D02*
X-261550Y-106460D01*
X-261760Y-106710D01*
X-261900Y-107010D01*
X-262005Y-107410D01*
X-262040Y-107860D01*
X-262005Y-108310D01*
X-261900Y-108710D01*
X-261760Y-109010D01*
X-261550Y-109260D01*
X-261270Y-109360D01*
X-260990Y-109260D01*
X-260780Y-109010D01*
X-260640Y-108710D01*
X-260535Y-108310D01*
X-260500Y-107860D01*
X-260535Y-107410D01*
X-260640Y-107010D01*
X-260780Y-106710D01*
X-260990Y-106460D01*
X-261270Y-106360D01*
G01X-253115Y-185500D02*
Y-182500D01*
X-251785D01*
G01X-252275Y-183950D02*
X-253115D01*
G01X-249370Y-183900D02*
X-249230Y-183750D01*
X-249125Y-183500D01*
X-249055Y-183150D01*
X-249125Y-182850D01*
X-249265Y-182650D01*
X-249510Y-182500D01*
X-250455D01*
Y-185500D01*
X-249300D01*
X-249055Y-185300D01*
X-248915Y-185000D01*
X-248845Y-184650D01*
X-248915Y-184300D01*
X-249125Y-184000D01*
X-249370Y-183900D01*
X-250455D01*
G01X-247620Y-184900D02*
X-247410Y-185250D01*
X-247130Y-185450D01*
X-246815Y-185500D01*
X-246535Y-185450D01*
X-246255Y-185200D01*
X-246080Y-184900D01*
X-246045Y-184600D01*
X-246115Y-184250D01*
X-246360Y-184000D01*
X-246605Y-183900D01*
X-246920D01*
G01X-246605D02*
X-246395Y-183750D01*
X-246220Y-183500D01*
X-246150Y-183200D01*
X-246220Y-182900D01*
X-246395Y-182650D01*
X-246710Y-182500D01*
X-247025Y-182550D01*
X-247340Y-182750D01*
G01X-241000Y-164000D02*
X-244000D01*
Y-163125D01*
X-243850Y-162845D01*
X-243650Y-162670D01*
X-243250Y-162600D01*
X-242850Y-162670D01*
X-242600Y-162880D01*
X-242450Y-163125D01*
Y-164000D01*
G01Y-163125D02*
X-241000Y-162600D01*
G01Y-160080D02*
X-244000D01*
X-241850Y-161375D01*
Y-159625D01*
G01X-241000Y-157700D02*
X-244000D01*
X-243400Y-158120D01*
G01X-241000D02*
Y-157280D01*
G01X-236500Y-164000D02*
X-239500D01*
Y-163125D01*
X-239350Y-162845D01*
X-239150Y-162670D01*
X-238750Y-162600D01*
X-238350Y-162670D01*
X-238100Y-162880D01*
X-237950Y-163125D01*
Y-164000D01*
G01Y-163125D02*
X-236500Y-162600D01*
G01Y-160080D02*
X-239500D01*
X-237350Y-161375D01*
Y-159625D01*
G01X-236950Y-158470D02*
X-236700Y-158260D01*
X-236550Y-158015D01*
X-236500Y-157700D01*
X-236600Y-157385D01*
X-236800Y-157140D01*
X-237150Y-156965D01*
X-237550Y-156930D01*
X-237950Y-157000D01*
X-238200Y-157175D01*
X-238400Y-157420D01*
X-238450Y-157665D01*
X-238400Y-157910D01*
X-238200Y-158225D01*
X-239500Y-158120D01*
Y-157175D01*
G01X-233115Y-185500D02*
Y-182500D01*
X-231785D01*
G01X-232275Y-183950D02*
X-233115D01*
G01X-229370Y-183900D02*
X-229230Y-183750D01*
X-229125Y-183500D01*
X-229055Y-183150D01*
X-229125Y-182850D01*
X-229265Y-182650D01*
X-229510Y-182500D01*
X-230455D01*
Y-185500D01*
X-229300D01*
X-229055Y-185300D01*
X-228915Y-185000D01*
X-228845Y-184650D01*
X-228915Y-184300D01*
X-229125Y-184000D01*
X-229370Y-183900D01*
X-230455D01*
G01X-226430Y-185500D02*
Y-182500D01*
X-227725Y-184650D01*
X-225975D01*
G01X-223965Y-185500D02*
Y-182500D01*
X-222635D01*
G01X-223125Y-183950D02*
X-223965D01*
G01X-221235Y-185100D02*
X-220955Y-185350D01*
X-220640Y-185500D01*
X-220360D01*
X-220080Y-185350D01*
X-219870Y-185100D01*
X-219765Y-184750D01*
X-219835Y-184400D01*
X-220010Y-184100D01*
X-220325Y-183900D01*
X-220745Y-183800D01*
X-220990Y-183600D01*
X-221095Y-183250D01*
X-221025Y-182900D01*
X-220850Y-182650D01*
X-220605Y-182500D01*
X-220360D01*
X-220115Y-182600D01*
X-219905Y-182850D01*
G01X-217280Y-185500D02*
Y-182500D01*
X-218575Y-184650D01*
X-216825D01*
G01X-222530Y-173750D02*
X-222740Y-173600D01*
X-222985Y-173500D01*
X-223265D01*
X-223580Y-173650D01*
X-223825Y-173900D01*
X-224000Y-174200D01*
X-224140Y-174700D01*
X-224175Y-175150D01*
X-224105Y-175600D01*
X-224000Y-175900D01*
X-223790Y-176200D01*
X-223545Y-176400D01*
X-223300Y-176500D01*
X-223055D01*
X-222810Y-176400D01*
X-222600Y-176250D01*
X-222425Y-176050D01*
G01X-220500Y-176500D02*
Y-173500D01*
X-220920Y-174100D01*
G01Y-176500D02*
X-220080D01*
G01X-217700Y-173500D02*
X-217980Y-173600D01*
X-218190Y-173850D01*
X-218330Y-174150D01*
X-218435Y-174550D01*
X-218470Y-175000D01*
X-218435Y-175450D01*
X-218330Y-175850D01*
X-218190Y-176150D01*
X-217980Y-176400D01*
X-217700Y-176500D01*
X-217420Y-176400D01*
X-217210Y-176150D01*
X-217070Y-175850D01*
X-216965Y-175450D01*
X-216930Y-175000D01*
X-216965Y-174550D01*
X-217070Y-174150D01*
X-217210Y-173850D01*
X-217420Y-173600D01*
X-217700Y-173500D01*
G01X-221630Y-168750D02*
X-221840Y-168600D01*
X-222085Y-168500D01*
X-222365D01*
X-222680Y-168650D01*
X-222925Y-168900D01*
X-223100Y-169200D01*
X-223240Y-169700D01*
X-223275Y-170150D01*
X-223205Y-170600D01*
X-223100Y-170900D01*
X-222890Y-171200D01*
X-222645Y-171400D01*
X-222400Y-171500D01*
X-222155D01*
X-221910Y-171400D01*
X-221700Y-171250D01*
X-221525Y-171050D01*
G01X-220195Y-171150D02*
X-219950Y-171400D01*
X-219670Y-171500D01*
X-219390Y-171400D01*
X-219145Y-171100D01*
X-218970Y-170650D01*
X-218900Y-170200D01*
Y-169650D01*
X-218970Y-169200D01*
X-219145Y-168800D01*
X-219355Y-168600D01*
X-219600Y-168500D01*
X-219880Y-168600D01*
X-220090Y-168800D01*
X-220230Y-169100D01*
X-220300Y-169500D01*
X-220230Y-169850D01*
X-220055Y-170200D01*
X-219845Y-170400D01*
X-219600Y-170450D01*
X-219320Y-170350D01*
X-219110Y-170100D01*
X-218900Y-169650D01*
G01X-225745Y-142950D02*
X-225535Y-142650D01*
X-225290Y-142500D01*
X-225010Y-142450D01*
X-224660Y-142550D01*
X-224415Y-142800D01*
X-224345Y-143100D01*
X-224380Y-143400D01*
X-224520Y-143650D01*
X-225220Y-144150D01*
X-225535Y-144500D01*
X-225745Y-145000D01*
X-225815Y-145450D01*
X-224345D01*
G01X-222280Y-142450D02*
X-222560Y-142550D01*
X-222770Y-142800D01*
X-222910Y-143100D01*
X-223015Y-143500D01*
X-223050Y-143950D01*
X-223015Y-144400D01*
X-222910Y-144800D01*
X-222770Y-145100D01*
X-222560Y-145350D01*
X-222280Y-145450D01*
X-222000Y-145350D01*
X-221790Y-145100D01*
X-221650Y-144800D01*
X-221545Y-144400D01*
X-221510Y-143950D01*
X-221545Y-143500D01*
X-221650Y-143100D01*
X-221790Y-142800D01*
X-222000Y-142550D01*
X-222280Y-142450D01*
G01X-218860Y-155330D02*
X-218685Y-155630D01*
X-218475Y-155830D01*
X-218230Y-155930D01*
X-217950Y-155830D01*
X-217740Y-155630D01*
X-217530Y-155330D01*
X-217460Y-154930D01*
Y-152930D01*
G01X-215360Y-155930D02*
Y-152930D01*
X-215780Y-153530D01*
G01Y-155930D02*
X-214940D01*
G01X-212560D02*
X-212315Y-155880D01*
X-212035Y-155730D01*
X-211860Y-155480D01*
X-211790Y-155130D01*
X-211860Y-154780D01*
X-212070Y-154480D01*
X-212385Y-154330D01*
X-212735D01*
X-212945Y-154230D01*
X-213120Y-153980D01*
X-213190Y-153630D01*
X-213085Y-153280D01*
X-212840Y-153030D01*
X-212560Y-152930D01*
X-212280Y-153030D01*
X-212035Y-153280D01*
X-211930Y-153630D01*
X-212000Y-153980D01*
X-212175Y-154230D01*
X-212385Y-154330D01*
X-212735D01*
X-213050Y-154480D01*
X-213260Y-154780D01*
X-213330Y-155130D01*
X-213260Y-155480D01*
X-213085Y-155730D01*
X-212805Y-155880D01*
X-212560Y-155930D01*
G01X-197500Y-96900D02*
X-197325Y-97200D01*
X-197115Y-97400D01*
X-196870Y-97500D01*
X-196590Y-97400D01*
X-196380Y-97200D01*
X-196170Y-96900D01*
X-196100Y-96500D01*
Y-94500D01*
G01X-194665Y-95000D02*
X-194455Y-94700D01*
X-194210Y-94550D01*
X-193930Y-94500D01*
X-193580Y-94600D01*
X-193335Y-94850D01*
X-193265Y-95150D01*
X-193300Y-95450D01*
X-193440Y-95700D01*
X-194140Y-96200D01*
X-194455Y-96550D01*
X-194665Y-97050D01*
X-194735Y-97500D01*
X-193265D01*
G01X-191865Y-95000D02*
X-191655Y-94700D01*
X-191410Y-94550D01*
X-191130Y-94500D01*
X-190780Y-94600D01*
X-190535Y-94850D01*
X-190465Y-95150D01*
X-190500Y-95450D01*
X-190640Y-95700D01*
X-191340Y-96200D01*
X-191655Y-96550D01*
X-191865Y-97050D01*
X-191935Y-97500D01*
X-190465D01*
G01X-191615Y-44680D02*
Y-41680D01*
X-190285D01*
G01X-190775Y-43130D02*
X-191615D01*
G01X-187870Y-43080D02*
X-187730Y-42930D01*
X-187625Y-42680D01*
X-187555Y-42330D01*
X-187625Y-42030D01*
X-187765Y-41830D01*
X-188010Y-41680D01*
X-188955D01*
Y-44680D01*
X-187800D01*
X-187555Y-44480D01*
X-187415Y-44180D01*
X-187345Y-43830D01*
X-187415Y-43480D01*
X-187625Y-43180D01*
X-187870Y-43080D01*
X-188955D01*
G01X-185420Y-44680D02*
X-185350Y-44030D01*
X-185245Y-43480D01*
X-185105Y-42980D01*
X-184930Y-42430D01*
X-184650Y-41680D01*
X-186050D01*
G01X-196540Y-38070D02*
X-196690Y-38280D01*
X-196790Y-38525D01*
Y-38805D01*
X-196640Y-39120D01*
X-196390Y-39365D01*
X-196090Y-39540D01*
X-195590Y-39680D01*
X-195140Y-39715D01*
X-194690Y-39645D01*
X-194390Y-39540D01*
X-194090Y-39330D01*
X-193890Y-39085D01*
X-193790Y-38840D01*
Y-38595D01*
X-193890Y-38350D01*
X-194040Y-38140D01*
X-194240Y-37965D01*
G01X-196290Y-36705D02*
X-196590Y-36495D01*
X-196740Y-36250D01*
X-196790Y-35970D01*
X-196690Y-35620D01*
X-196440Y-35375D01*
X-196140Y-35305D01*
X-195840Y-35340D01*
X-195590Y-35480D01*
X-195090Y-36180D01*
X-194740Y-36495D01*
X-194240Y-36705D01*
X-193790Y-36775D01*
Y-35305D01*
G01X-194390Y-34010D02*
X-194040Y-33800D01*
X-193840Y-33520D01*
X-193790Y-33205D01*
X-193840Y-32925D01*
X-194090Y-32645D01*
X-194390Y-32470D01*
X-194690Y-32435D01*
X-195040Y-32505D01*
X-195290Y-32750D01*
X-195390Y-32995D01*
Y-33310D01*
G01Y-32995D02*
X-195540Y-32785D01*
X-195790Y-32610D01*
X-196090Y-32540D01*
X-196390Y-32610D01*
X-196640Y-32785D01*
X-196790Y-33100D01*
X-196740Y-33415D01*
X-196540Y-33730D01*
G01X-197462Y-52380D02*
X-197612Y-52590D01*
X-197712Y-52835D01*
Y-53115D01*
X-197562Y-53430D01*
X-197312Y-53675D01*
X-197012Y-53850D01*
X-196512Y-53990D01*
X-196062Y-54025D01*
X-195612Y-53955D01*
X-195312Y-53850D01*
X-195012Y-53640D01*
X-194812Y-53395D01*
X-194712Y-53150D01*
Y-52905D01*
X-194812Y-52660D01*
X-194962Y-52450D01*
X-195162Y-52275D01*
G01X-194712Y-50350D02*
X-197712D01*
X-197112Y-50770D01*
G01X-194712D02*
Y-49930D01*
G01Y-47550D02*
X-194762Y-47305D01*
X-194912Y-47025D01*
X-195162Y-46850D01*
X-195512Y-46780D01*
X-195862Y-46850D01*
X-196162Y-47060D01*
X-196312Y-47375D01*
Y-47725D01*
X-196412Y-47935D01*
X-196662Y-48110D01*
X-197012Y-48180D01*
X-197362Y-48075D01*
X-197612Y-47830D01*
X-197712Y-47550D01*
X-197612Y-47270D01*
X-197362Y-47025D01*
X-197012Y-46920D01*
X-196662Y-46990D01*
X-196412Y-47165D01*
X-196312Y-47375D01*
Y-47725D01*
X-196162Y-48040D01*
X-195862Y-48250D01*
X-195512Y-48320D01*
X-195162Y-48250D01*
X-194912Y-48075D01*
X-194762Y-47795D01*
X-194712Y-47550D01*
G01X-196540Y-13340D02*
X-196690Y-13550D01*
X-196790Y-13795D01*
Y-14075D01*
X-196640Y-14390D01*
X-196390Y-14635D01*
X-196090Y-14810D01*
X-195590Y-14950D01*
X-195140Y-14985D01*
X-194690Y-14915D01*
X-194390Y-14810D01*
X-194090Y-14600D01*
X-193890Y-14355D01*
X-193790Y-14110D01*
Y-13865D01*
X-193890Y-13620D01*
X-194040Y-13410D01*
X-194240Y-13235D01*
G01X-196290Y-11975D02*
X-196590Y-11765D01*
X-196740Y-11520D01*
X-196790Y-11240D01*
X-196690Y-10890D01*
X-196440Y-10645D01*
X-196140Y-10575D01*
X-195840Y-10610D01*
X-195590Y-10750D01*
X-195090Y-11450D01*
X-194740Y-11765D01*
X-194240Y-11975D01*
X-193790Y-12045D01*
Y-10575D01*
G01Y-8090D02*
X-196790D01*
X-194640Y-9385D01*
Y-7635D01*
G01X-188940Y-62790D02*
X-189090Y-63000D01*
X-189190Y-63245D01*
Y-63525D01*
X-189040Y-63840D01*
X-188790Y-64085D01*
X-188490Y-64260D01*
X-187990Y-64400D01*
X-187540Y-64435D01*
X-187090Y-64365D01*
X-186790Y-64260D01*
X-186490Y-64050D01*
X-186290Y-63805D01*
X-186190Y-63560D01*
Y-63315D01*
X-186290Y-63070D01*
X-186440Y-62860D01*
X-186640Y-62685D01*
G01X-186190Y-60760D02*
X-189190D01*
X-188590Y-61180D01*
G01X-186190D02*
Y-60340D01*
G01Y-58030D02*
X-186840Y-57960D01*
X-187390Y-57855D01*
X-187890Y-57715D01*
X-188440Y-57540D01*
X-189190Y-57260D01*
Y-58660D01*
G01X-181500Y-58500D02*
Y-55500D01*
X-180625D01*
X-180345Y-55650D01*
X-180170Y-55850D01*
X-180100Y-56250D01*
X-180170Y-56650D01*
X-180380Y-56900D01*
X-180625Y-57050D01*
X-181500D01*
G01X-180625D02*
X-180100Y-58500D01*
G01X-178665Y-57250D02*
X-178420Y-56900D01*
X-178210Y-56700D01*
X-177930Y-56600D01*
X-177685Y-56700D01*
X-177510Y-56900D01*
X-177370Y-57200D01*
X-177335Y-57550D01*
X-177370Y-57850D01*
X-177510Y-58150D01*
X-177720Y-58400D01*
X-177965Y-58500D01*
X-178245Y-58400D01*
X-178490Y-58100D01*
X-178630Y-57650D01*
X-178665Y-57150D01*
X-178595Y-56500D01*
X-178490Y-56150D01*
X-178315Y-55800D01*
X-178070Y-55550D01*
X-177825Y-55500D01*
X-177580Y-55600D01*
X-177405Y-55850D01*
G01X-175200Y-55500D02*
X-175480Y-55600D01*
X-175690Y-55850D01*
X-175830Y-56150D01*
X-175935Y-56550D01*
X-175970Y-57000D01*
X-175935Y-57450D01*
X-175830Y-57850D01*
X-175690Y-58150D01*
X-175480Y-58400D01*
X-175200Y-58500D01*
X-174920Y-58400D01*
X-174710Y-58150D01*
X-174570Y-57850D01*
X-174465Y-57450D01*
X-174430Y-57000D01*
X-174465Y-56550D01*
X-174570Y-56150D01*
X-174710Y-55850D01*
X-174920Y-55600D01*
X-175200Y-55500D01*
G01X-181260Y-63440D02*
Y-60440D01*
X-180350Y-62940D01*
X-179440Y-60440D01*
Y-63440D01*
G01X-178285D02*
Y-60440D01*
G01X-176815D02*
Y-63440D01*
G01Y-61940D02*
X-178285D01*
G01X-175520Y-62990D02*
X-175310Y-63240D01*
X-175065Y-63390D01*
X-174750Y-63440D01*
X-174435Y-63340D01*
X-174190Y-63140D01*
X-174015Y-62790D01*
X-173980Y-62390D01*
X-174050Y-61990D01*
X-174225Y-61740D01*
X-174470Y-61540D01*
X-174715Y-61490D01*
X-174960Y-61540D01*
X-175275Y-61740D01*
X-175170Y-60440D01*
X-174225D01*
G01X-180480Y-37760D02*
X-180690Y-37610D01*
X-180935Y-37510D01*
X-181215D01*
X-181530Y-37660D01*
X-181775Y-37910D01*
X-181950Y-38210D01*
X-182090Y-38710D01*
X-182125Y-39160D01*
X-182055Y-39610D01*
X-181950Y-39910D01*
X-181740Y-40210D01*
X-181495Y-40410D01*
X-181250Y-40510D01*
X-181005D01*
X-180760Y-40410D01*
X-180550Y-40260D01*
X-180375Y-40060D01*
G01X-178450Y-40510D02*
Y-37510D01*
X-178870Y-38110D01*
G01Y-40510D02*
X-178030D01*
G01X-176245Y-40160D02*
X-176000Y-40410D01*
X-175720Y-40510D01*
X-175440Y-40410D01*
X-175195Y-40110D01*
X-175020Y-39660D01*
X-174950Y-39210D01*
Y-38660D01*
X-175020Y-38210D01*
X-175195Y-37810D01*
X-175405Y-37610D01*
X-175650Y-37510D01*
X-175930Y-37610D01*
X-176140Y-37810D01*
X-176280Y-38110D01*
X-176350Y-38510D01*
X-176280Y-38860D01*
X-176105Y-39210D01*
X-175895Y-39410D01*
X-175650Y-39460D01*
X-175370Y-39360D01*
X-175160Y-39110D01*
X-174950Y-38660D01*
G01X-186260Y-20940D02*
X-186410Y-21150D01*
X-186510Y-21395D01*
Y-21675D01*
X-186360Y-21990D01*
X-186110Y-22235D01*
X-185810Y-22410D01*
X-185310Y-22550D01*
X-184860Y-22585D01*
X-184410Y-22515D01*
X-184110Y-22410D01*
X-183810Y-22200D01*
X-183610Y-21955D01*
X-183510Y-21710D01*
Y-21465D01*
X-183610Y-21220D01*
X-183760Y-21010D01*
X-183960Y-20835D01*
G01X-186010Y-19575D02*
X-186310Y-19365D01*
X-186460Y-19120D01*
X-186510Y-18840D01*
X-186410Y-18490D01*
X-186160Y-18245D01*
X-185860Y-18175D01*
X-185560Y-18210D01*
X-185310Y-18350D01*
X-184810Y-19050D01*
X-184460Y-19365D01*
X-183960Y-19575D01*
X-183510Y-19645D01*
Y-18175D01*
G01X-186510Y-16110D02*
X-186410Y-16390D01*
X-186160Y-16600D01*
X-185860Y-16740D01*
X-185460Y-16845D01*
X-185010Y-16880D01*
X-184560Y-16845D01*
X-184160Y-16740D01*
X-183860Y-16600D01*
X-183610Y-16390D01*
X-183510Y-16110D01*
X-183610Y-15830D01*
X-183860Y-15620D01*
X-184160Y-15480D01*
X-184560Y-15375D01*
X-185010Y-15340D01*
X-185460Y-15375D01*
X-185860Y-15480D01*
X-186160Y-15620D01*
X-186410Y-15830D01*
X-186510Y-16110D01*
G01X-161423Y-94053D02*
X-161213Y-93753D01*
X-160968Y-93603D01*
X-160688Y-93553D01*
X-160338Y-93653D01*
X-160093Y-93903D01*
X-160023Y-94203D01*
X-160058Y-94503D01*
X-160198Y-94753D01*
X-160898Y-95253D01*
X-161213Y-95603D01*
X-161423Y-96103D01*
X-161493Y-96553D01*
X-160023D01*
G01X-158728D02*
Y-93553D01*
X-158028D01*
X-157748Y-93703D01*
X-157538Y-93903D01*
X-157363Y-94203D01*
X-157223Y-94553D01*
X-157188Y-95053D01*
X-157223Y-95553D01*
X-157363Y-95903D01*
X-157538Y-96203D01*
X-157748Y-96403D01*
X-158028Y-96553D01*
X-158728D01*
G01X-160193Y-79839D02*
X-159983Y-79539D01*
X-159738Y-79389D01*
X-159458Y-79339D01*
X-159108Y-79439D01*
X-158863Y-79689D01*
X-158793Y-79989D01*
X-158828Y-80289D01*
X-158968Y-80539D01*
X-159668Y-81039D01*
X-159983Y-81389D01*
X-160193Y-81889D01*
X-160263Y-82339D01*
X-158793D01*
G01X-155958Y-79589D02*
X-156168Y-79439D01*
X-156413Y-79339D01*
X-156693D01*
X-157008Y-79489D01*
X-157253Y-79739D01*
X-157428Y-80039D01*
X-157568Y-80539D01*
X-157603Y-80989D01*
X-157533Y-81439D01*
X-157428Y-81739D01*
X-157218Y-82039D01*
X-156973Y-82239D01*
X-156728Y-82339D01*
X-156483D01*
X-156238Y-82239D01*
X-156028Y-82089D01*
X-155853Y-81889D01*
G01X-161423Y-64525D02*
X-161213Y-64225D01*
X-160968Y-64075D01*
X-160688Y-64025D01*
X-160338Y-64125D01*
X-160093Y-64375D01*
X-160023Y-64675D01*
X-160058Y-64975D01*
X-160198Y-65225D01*
X-160898Y-65725D01*
X-161213Y-66075D01*
X-161423Y-66575D01*
X-161493Y-67025D01*
X-160023D01*
G01X-157678Y-65425D02*
X-157538Y-65275D01*
X-157433Y-65025D01*
X-157363Y-64675D01*
X-157433Y-64375D01*
X-157573Y-64175D01*
X-157818Y-64025D01*
X-158763D01*
Y-67025D01*
X-157608D01*
X-157363Y-66825D01*
X-157223Y-66525D01*
X-157153Y-66175D01*
X-157223Y-65825D01*
X-157433Y-65525D01*
X-157678Y-65425D01*
X-158763D01*
G01X-161423Y-45824D02*
X-161213Y-45524D01*
X-160968Y-45374D01*
X-160688Y-45324D01*
X-160338Y-45424D01*
X-160093Y-45674D01*
X-160023Y-45974D01*
X-160058Y-46274D01*
X-160198Y-46524D01*
X-160898Y-47024D01*
X-161213Y-47374D01*
X-161423Y-47874D01*
X-161493Y-48324D01*
X-160023D01*
G01X-158833D02*
X-157958Y-45324D01*
X-157083Y-48324D01*
G01X-157398Y-47274D02*
X-158518D01*
G01X-168910Y-49485D02*
X-171910D01*
Y-48155D01*
G01X-170460Y-48645D02*
Y-49485D01*
G01X-169310Y-46755D02*
X-169060Y-46475D01*
X-168910Y-46160D01*
Y-45880D01*
X-169060Y-45600D01*
X-169310Y-45390D01*
X-169660Y-45285D01*
X-170010Y-45355D01*
X-170310Y-45530D01*
X-170510Y-45845D01*
X-170610Y-46265D01*
X-170810Y-46510D01*
X-171160Y-46615D01*
X-171510Y-46545D01*
X-171760Y-46370D01*
X-171910Y-46125D01*
Y-45880D01*
X-171810Y-45635D01*
X-171560Y-45425D01*
G01X-168910Y-43290D02*
X-169560Y-43220D01*
X-170110Y-43115D01*
X-170610Y-42975D01*
X-171160Y-42800D01*
X-171910Y-42520D01*
Y-43920D01*
G01X-168115Y-31000D02*
Y-28000D01*
X-166785D01*
G01X-167275Y-29450D02*
X-168115D01*
G01X-164370Y-29400D02*
X-164230Y-29250D01*
X-164125Y-29000D01*
X-164055Y-28650D01*
X-164125Y-28350D01*
X-164265Y-28150D01*
X-164510Y-28000D01*
X-165455D01*
Y-31000D01*
X-164300D01*
X-164055Y-30800D01*
X-163915Y-30500D01*
X-163845Y-30150D01*
X-163915Y-29800D01*
X-164125Y-29500D01*
X-164370Y-29400D01*
X-165455D01*
G01X-162620Y-30550D02*
X-162410Y-30800D01*
X-162165Y-30950D01*
X-161850Y-31000D01*
X-161535Y-30900D01*
X-161290Y-30700D01*
X-161115Y-30350D01*
X-161080Y-29950D01*
X-161150Y-29550D01*
X-161325Y-29300D01*
X-161570Y-29100D01*
X-161815Y-29050D01*
X-162060Y-29100D01*
X-162375Y-29300D01*
X-162270Y-28000D01*
X-161325D01*
G01X-167965Y-26000D02*
Y-23000D01*
X-166635D01*
G01X-167125Y-24450D02*
X-167965D01*
G01X-165235Y-25600D02*
X-164955Y-25850D01*
X-164640Y-26000D01*
X-164360D01*
X-164080Y-25850D01*
X-163870Y-25600D01*
X-163765Y-25250D01*
X-163835Y-24900D01*
X-164010Y-24600D01*
X-164325Y-24400D01*
X-164745Y-24300D01*
X-164990Y-24100D01*
X-165095Y-23750D01*
X-165025Y-23400D01*
X-164850Y-23150D01*
X-164605Y-23000D01*
X-164360D01*
X-164115Y-23100D01*
X-163905Y-23350D01*
G01X-162470Y-25550D02*
X-162260Y-25800D01*
X-162015Y-25950D01*
X-161700Y-26000D01*
X-161385Y-25900D01*
X-161140Y-25700D01*
X-160965Y-25350D01*
X-160930Y-24950D01*
X-161000Y-24550D01*
X-161175Y-24300D01*
X-161420Y-24100D01*
X-161665Y-24050D01*
X-161910Y-24100D01*
X-162225Y-24300D01*
X-162120Y-23000D01*
X-161175D01*
G01X-168500Y-36000D02*
Y-33000D01*
X-167625D01*
X-167345Y-33150D01*
X-167170Y-33350D01*
X-167100Y-33750D01*
X-167170Y-34150D01*
X-167380Y-34400D01*
X-167625Y-34550D01*
X-168500D01*
G01X-167625D02*
X-167100Y-36000D01*
G01X-165770Y-35550D02*
X-165560Y-35800D01*
X-165315Y-35950D01*
X-165000Y-36000D01*
X-164685Y-35900D01*
X-164440Y-35700D01*
X-164265Y-35350D01*
X-164230Y-34950D01*
X-164300Y-34550D01*
X-164475Y-34300D01*
X-164720Y-34100D01*
X-164965Y-34050D01*
X-165210Y-34100D01*
X-165525Y-34300D01*
X-165420Y-33000D01*
X-164475D01*
G01X-162200Y-36000D02*
X-161955Y-35950D01*
X-161675Y-35800D01*
X-161500Y-35550D01*
X-161430Y-35200D01*
X-161500Y-34850D01*
X-161710Y-34550D01*
X-162025Y-34400D01*
X-162375D01*
X-162585Y-34300D01*
X-162760Y-34050D01*
X-162830Y-33700D01*
X-162725Y-33350D01*
X-162480Y-33100D01*
X-162200Y-33000D01*
X-161920Y-33100D01*
X-161675Y-33350D01*
X-161570Y-33700D01*
X-161640Y-34050D01*
X-161815Y-34300D01*
X-162025Y-34400D01*
X-162375D01*
X-162690Y-34550D01*
X-162900Y-34850D01*
X-162970Y-35200D01*
X-162900Y-35550D01*
X-162725Y-35800D01*
X-162445Y-35950D01*
X-162200Y-36000D01*
G01X-168090Y-11310D02*
Y-8310D01*
X-167215D01*
X-166935Y-8460D01*
X-166760Y-8660D01*
X-166690Y-9060D01*
X-166760Y-9460D01*
X-166970Y-9710D01*
X-167215Y-9860D01*
X-168090D01*
G01X-167215D02*
X-166690Y-11310D01*
G01X-165360Y-10860D02*
X-165150Y-11110D01*
X-164905Y-11260D01*
X-164590Y-11310D01*
X-164275Y-11210D01*
X-164030Y-11010D01*
X-163855Y-10660D01*
X-163820Y-10260D01*
X-163890Y-9860D01*
X-164065Y-9610D01*
X-164310Y-9410D01*
X-164555Y-9360D01*
X-164800Y-9410D01*
X-165115Y-9610D01*
X-165010Y-8310D01*
X-164065D01*
G01X-162385Y-10960D02*
X-162140Y-11210D01*
X-161860Y-11310D01*
X-161580Y-11210D01*
X-161335Y-10910D01*
X-161160Y-10460D01*
X-161090Y-10010D01*
Y-9460D01*
X-161160Y-9010D01*
X-161335Y-8610D01*
X-161545Y-8410D01*
X-161790Y-8310D01*
X-162070Y-8410D01*
X-162280Y-8610D01*
X-162420Y-8910D01*
X-162490Y-9310D01*
X-162420Y-9660D01*
X-162245Y-10010D01*
X-162035Y-10210D01*
X-161790Y-10260D01*
X-161510Y-10160D01*
X-161300Y-9910D01*
X-161090Y-9460D01*
G01X-166620Y-17350D02*
X-166830Y-17200D01*
X-167075Y-17100D01*
X-167355D01*
X-167670Y-17250D01*
X-167915Y-17500D01*
X-168090Y-17800D01*
X-168230Y-18300D01*
X-168265Y-18750D01*
X-168195Y-19200D01*
X-168090Y-19500D01*
X-167880Y-19800D01*
X-167635Y-20000D01*
X-167390Y-20100D01*
X-167145D01*
X-166900Y-20000D01*
X-166690Y-19850D01*
X-166515Y-19650D01*
G01X-165255Y-17600D02*
X-165045Y-17300D01*
X-164800Y-17150D01*
X-164520Y-17100D01*
X-164170Y-17200D01*
X-163925Y-17450D01*
X-163855Y-17750D01*
X-163890Y-18050D01*
X-164030Y-18300D01*
X-164730Y-18800D01*
X-165045Y-19150D01*
X-165255Y-19650D01*
X-165325Y-20100D01*
X-163855D01*
G01X-161860D02*
X-161790Y-19450D01*
X-161685Y-18900D01*
X-161545Y-18400D01*
X-161370Y-17850D01*
X-161090Y-17100D01*
X-162490D01*
G01X-168615Y-6500D02*
Y-3500D01*
X-167285D01*
G01X-167775Y-4950D02*
X-168615D01*
G01X-164870Y-4900D02*
X-164730Y-4750D01*
X-164625Y-4500D01*
X-164555Y-4150D01*
X-164625Y-3850D01*
X-164765Y-3650D01*
X-165010Y-3500D01*
X-165955D01*
Y-6500D01*
X-164800D01*
X-164555Y-6300D01*
X-164415Y-6000D01*
X-164345Y-5650D01*
X-164415Y-5300D01*
X-164625Y-5000D01*
X-164870Y-4900D01*
X-165955D01*
G01X-163015Y-5250D02*
X-162770Y-4900D01*
X-162560Y-4700D01*
X-162280Y-4600D01*
X-162035Y-4700D01*
X-161860Y-4900D01*
X-161720Y-5200D01*
X-161685Y-5550D01*
X-161720Y-5850D01*
X-161860Y-6150D01*
X-162070Y-6400D01*
X-162315Y-6500D01*
X-162595Y-6400D01*
X-162840Y-6100D01*
X-162980Y-5650D01*
X-163015Y-5150D01*
X-162945Y-4500D01*
X-162840Y-4150D01*
X-162665Y-3800D01*
X-162420Y-3550D01*
X-162175Y-3500D01*
X-161930Y-3600D01*
X-161755Y-3850D01*
G01X-168465Y-500D02*
Y2500D01*
X-167135D01*
G01X-167625Y1050D02*
X-168465D01*
G01X-165735Y-100D02*
X-165455Y-350D01*
X-165140Y-500D01*
X-164860D01*
X-164580Y-350D01*
X-164370Y-100D01*
X-164265Y250D01*
X-164335Y600D01*
X-164510Y900D01*
X-164825Y1100D01*
X-165245Y1200D01*
X-165490Y1400D01*
X-165595Y1750D01*
X-165525Y2100D01*
X-165350Y2350D01*
X-165105Y2500D01*
X-164860D01*
X-164615Y2400D01*
X-164405Y2150D01*
G01X-162865Y750D02*
X-162620Y1100D01*
X-162410Y1300D01*
X-162130Y1400D01*
X-161885Y1300D01*
X-161710Y1100D01*
X-161570Y800D01*
X-161535Y450D01*
X-161570Y150D01*
X-161710Y-150D01*
X-161920Y-400D01*
X-162165Y-500D01*
X-162445Y-400D01*
X-162690Y-100D01*
X-162830Y350D01*
X-162865Y850D01*
X-162795Y1500D01*
X-162690Y1850D01*
X-162515Y2200D01*
X-162270Y2450D01*
X-162025Y2500D01*
X-161780Y2400D01*
X-161605Y2150D01*
G01X-155074Y-180402D02*
X-154199Y-177402D01*
X-153324Y-180402D01*
G01X-153639Y-179352D02*
X-154759D01*
G01X-152064Y-179152D02*
X-151819Y-178802D01*
X-151609Y-178602D01*
X-151329Y-178502D01*
X-151084Y-178602D01*
X-150909Y-178802D01*
X-150769Y-179102D01*
X-150734Y-179452D01*
X-150769Y-179752D01*
X-150909Y-180052D01*
X-151119Y-180302D01*
X-151364Y-180402D01*
X-151644Y-180302D01*
X-151889Y-180002D01*
X-152029Y-179552D01*
X-152064Y-179052D01*
X-151994Y-178402D01*
X-151889Y-178052D01*
X-151714Y-177702D01*
X-151469Y-177452D01*
X-151224Y-177402D01*
X-150979Y-177502D01*
X-150804Y-177752D01*
G01X-153499Y-158354D02*
X-154899D01*
Y-155354D01*
X-153499D01*
G01X-154059Y-156804D02*
X-154899D01*
G01X-152064Y-157104D02*
X-151819Y-156754D01*
X-151609Y-156554D01*
X-151329Y-156454D01*
X-151084Y-156554D01*
X-150909Y-156754D01*
X-150769Y-157054D01*
X-150734Y-157404D01*
X-150769Y-157704D01*
X-150909Y-158004D01*
X-151119Y-158254D01*
X-151364Y-158354D01*
X-151644Y-158254D01*
X-151889Y-157954D01*
X-152029Y-157504D01*
X-152064Y-157004D01*
X-151994Y-156354D01*
X-151889Y-156004D01*
X-151714Y-155654D01*
X-151469Y-155404D01*
X-151224Y-155354D01*
X-150979Y-155454D01*
X-150804Y-155704D01*
G01X-154619Y-133307D02*
X-153779D01*
G01X-154199D02*
Y-136307D01*
G01X-154619D02*
X-153779D01*
G01X-152064Y-135057D02*
X-151819Y-134707D01*
X-151609Y-134507D01*
X-151329Y-134407D01*
X-151084Y-134507D01*
X-150909Y-134707D01*
X-150769Y-135007D01*
X-150734Y-135357D01*
X-150769Y-135657D01*
X-150909Y-135957D01*
X-151119Y-136207D01*
X-151364Y-136307D01*
X-151644Y-136207D01*
X-151889Y-135907D01*
X-152029Y-135457D01*
X-152064Y-134957D01*
X-151994Y-134307D01*
X-151889Y-133957D01*
X-151714Y-133607D01*
X-151469Y-133357D01*
X-151224Y-133307D01*
X-150979Y-133407D01*
X-150804Y-133657D01*
G01X-128224Y-116006D02*
X-128049Y-116306D01*
X-127839Y-116506D01*
X-127594Y-116606D01*
X-127314Y-116506D01*
X-127104Y-116306D01*
X-126894Y-116006D01*
X-126824Y-115606D01*
Y-113606D01*
G01X-125389Y-114106D02*
X-125179Y-113806D01*
X-124934Y-113656D01*
X-124654Y-113606D01*
X-124304Y-113706D01*
X-124059Y-113956D01*
X-123989Y-114256D01*
X-124024Y-114556D01*
X-124164Y-114806D01*
X-124864Y-115306D01*
X-125179Y-115656D01*
X-125389Y-116156D01*
X-125459Y-116606D01*
X-123989D01*
G01X-122694Y-116006D02*
X-122484Y-116356D01*
X-122204Y-116556D01*
X-121889Y-116606D01*
X-121609Y-116556D01*
X-121329Y-116306D01*
X-121154Y-116006D01*
X-121119Y-115706D01*
X-121189Y-115356D01*
X-121434Y-115106D01*
X-121679Y-115006D01*
X-121994D01*
G01X-121679D02*
X-121469Y-114856D01*
X-121294Y-114606D01*
X-121224Y-114306D01*
X-121294Y-114006D01*
X-121469Y-113756D01*
X-121784Y-113606D01*
X-122099Y-113656D01*
X-122414Y-113856D01*
G01X-99925Y-180902D02*
X-99050Y-177902D01*
X-98175Y-180902D01*
G01X-98490Y-179852D02*
X-99610D01*
G01X-96250Y-180902D02*
Y-177902D01*
X-96670Y-178502D01*
G01Y-180902D02*
X-95830D01*
G01X-98350Y-158854D02*
X-99750D01*
Y-155854D01*
X-98350D01*
G01X-98910Y-157304D02*
X-99750D01*
G01X-96250Y-158854D02*
Y-155854D01*
X-96670Y-156454D01*
G01Y-158854D02*
X-95830D01*
G01X-99470Y-133807D02*
X-98630D01*
G01X-99050D02*
Y-136807D01*
G01X-99470D02*
X-98630D01*
G01X-96250D02*
Y-133807D01*
X-96670Y-134407D01*
G01Y-136807D02*
X-95830D01*
G01X-93500Y-113900D02*
X-93325Y-114200D01*
X-93115Y-114400D01*
X-92870Y-114500D01*
X-92590Y-114400D01*
X-92380Y-114200D01*
X-92170Y-113900D01*
X-92100Y-113500D01*
Y-111500D01*
G01X-90665Y-112000D02*
X-90455Y-111700D01*
X-90210Y-111550D01*
X-89930Y-111500D01*
X-89580Y-111600D01*
X-89335Y-111850D01*
X-89265Y-112150D01*
X-89300Y-112450D01*
X-89440Y-112700D01*
X-90140Y-113200D01*
X-90455Y-113550D01*
X-90665Y-114050D01*
X-90735Y-114500D01*
X-89265D01*
G01X-86780D02*
Y-111500D01*
X-88075Y-113650D01*
X-86325D01*
G01X-69000Y-178500D02*
X-72000D01*
Y-177625D01*
X-71850Y-177345D01*
X-71650Y-177170D01*
X-71250Y-177100D01*
X-70850Y-177170D01*
X-70600Y-177380D01*
X-70450Y-177625D01*
Y-178500D01*
G01Y-177625D02*
X-69000Y-177100D01*
G01Y-175070D02*
X-69650Y-175000D01*
X-70200Y-174895D01*
X-70700Y-174755D01*
X-71250Y-174580D01*
X-72000Y-174300D01*
Y-175700D01*
G01X-69000Y-172200D02*
X-72000D01*
X-71400Y-172620D01*
G01X-69000D02*
Y-171780D01*
G01X-65270Y-100053D02*
Y-97053D01*
X-65690Y-97653D01*
G01Y-100053D02*
X-64850D01*
G01X-63240D02*
Y-97053D01*
X-62540D01*
X-62260Y-97203D01*
X-62050Y-97403D01*
X-61875Y-97703D01*
X-61735Y-98053D01*
X-61700Y-98553D01*
X-61735Y-99053D01*
X-61875Y-99403D01*
X-62050Y-99703D01*
X-62260Y-99903D01*
X-62540Y-100053D01*
X-63240D01*
G01X-65270Y-70525D02*
Y-67525D01*
X-65690Y-68125D01*
G01Y-70525D02*
X-64850D01*
G01X-62190Y-68925D02*
X-62050Y-68775D01*
X-61945Y-68525D01*
X-61875Y-68175D01*
X-61945Y-67875D01*
X-62085Y-67675D01*
X-62330Y-67525D01*
X-63275D01*
Y-70525D01*
X-62120D01*
X-61875Y-70325D01*
X-61735Y-70025D01*
X-61665Y-69675D01*
X-61735Y-69325D01*
X-61945Y-69025D01*
X-62190Y-68925D01*
X-63275D01*
G01X-65270Y-85289D02*
Y-82289D01*
X-65690Y-82889D01*
G01Y-85289D02*
X-64850D01*
G01X-61700Y-82539D02*
X-61910Y-82389D01*
X-62155Y-82289D01*
X-62435D01*
X-62750Y-82439D01*
X-62995Y-82689D01*
X-63170Y-82989D01*
X-63310Y-83489D01*
X-63345Y-83939D01*
X-63275Y-84389D01*
X-63170Y-84689D01*
X-62960Y-84989D01*
X-62715Y-85189D01*
X-62470Y-85289D01*
X-62225D01*
X-61980Y-85189D01*
X-61770Y-85039D01*
X-61595Y-84839D01*
G01X-62400Y-53500D02*
Y-50500D01*
X-62820Y-51100D01*
G01Y-53500D02*
X-61980D01*
G01X-60475D02*
X-59600Y-50500D01*
X-58725Y-53500D01*
G01X-59040Y-52450D02*
X-60160D01*
G01X3180Y-149953D02*
Y-146953D01*
X4090Y-149453D01*
X5000Y-146953D01*
Y-149953D01*
G01X6155D02*
Y-146953D01*
G01X7625D02*
Y-149953D01*
G01Y-148453D02*
X6155D01*
G01X9025Y-148703D02*
X9270Y-148353D01*
X9480Y-148153D01*
X9760Y-148053D01*
X10005Y-148153D01*
X10180Y-148353D01*
X10320Y-148653D01*
X10355Y-149003D01*
X10320Y-149303D01*
X10180Y-149603D01*
X9970Y-149853D01*
X9725Y-149953D01*
X9445Y-149853D01*
X9200Y-149553D01*
X9060Y-149103D01*
X9025Y-148603D01*
X9095Y-147953D01*
X9200Y-147603D01*
X9375Y-147253D01*
X9620Y-147003D01*
X9865Y-146953D01*
X10110Y-147053D01*
X10285Y-147303D01*
G01X-1423750Y0D02*
X-1418000D01*
G01X-1410000Y-8000D02*
Y-13750D01*
G01Y13750D02*
Y8100D01*
G01X-1402000Y0D02*
X-1396250D01*
G01X-1200000Y-600000D02*
X-575000D01*
Y-440000D01*
X-1200000D01*
Y-600000D01*
G01X-927050Y-62400D02*
Y-37400D01*
X-789550D01*
Y-62400D01*
X-927050D01*
G01X-13750Y-136453D02*
X-8000D01*
G01X-13750Y0D02*
X-8000D01*
G01X0Y-144453D02*
Y-150203D01*
G01X8000Y-136453D02*
X13750D01*
G01X0Y-122703D02*
Y-128353D01*
G01X0Y-8000D02*
Y-13750D01*
G01X8000Y0D02*
X13750D01*
G01X0Y13750D02*
Y8100D01*
G54D15*
G01X-1655890Y-123468D02*
Y-129374D01*
X-1649984D01*
G01Y-90004D02*
X-1655890D01*
Y-95909D01*
G01X-1643291Y-129374D02*
X-1637386D01*
Y-123468D01*
G01Y-95909D02*
Y-90004D01*
X-1643291D01*
G01X-1541378Y-84882D02*
Y-225827D01*
X-1619724D01*
Y-84882D01*
X-1541378D01*
G01X-1520500Y-122800D02*
X-1517500D01*
G01X-1497843Y-58790D02*
Y-184990D01*
X-1455543D01*
Y-58790D01*
X-1497843D01*
G01X-1397600Y-134100D02*
X-1394600D01*
G01X-1335924Y-102205D02*
Y-195236D01*
X-1345963D01*
Y-312953D01*
X-1367814D01*
Y-195236D01*
X-1377853D01*
Y-102205D01*
X-1335924D01*
G01X-1355000Y-18600D02*
X-1358000D01*
G01X-1341050Y-20619D02*
Y-21119D01*
X-1331050D01*
Y-10619D01*
G01X-1331100Y-1500D02*
Y-1000D01*
X-1341100D01*
Y-11500D01*
G01X-1335335Y-221299D02*
Y-105945D01*
X-1288681D01*
Y-221299D01*
X-1335335D01*
G01X-1323000Y-19400D02*
X-1326000D01*
G01X-1318228Y-83350D02*
X-1315228D01*
G01X-1319200Y-66500D02*
X-1316200D01*
G01X-1310250Y-21519D02*
Y-22019D01*
X-1300250D01*
Y-11519D01*
G01X-1300300Y-2400D02*
Y-1900D01*
X-1310300D01*
Y-12400D01*
G01X-1305000Y-81200D02*
Y-78200D01*
G01Y-72700D02*
Y-75700D01*
G01Y-70200D02*
Y-67200D01*
G01Y-61700D02*
Y-64700D01*
G01Y-56200D02*
Y-59200D01*
G01Y-50700D02*
Y-53700D01*
G01Y-39700D02*
Y-42700D01*
G01Y-48200D02*
Y-45200D01*
G01Y-28700D02*
Y-31700D01*
G01Y-34200D02*
Y-37200D01*
G01X-1283950Y-184580D02*
X-1273950D01*
G01X-1283960Y-176590D02*
Y-184590D01*
G01X-1283957Y-168346D02*
Y-133898D01*
G01X-1274689Y-176220D02*
X-1280906D01*
Y-147647D01*
G01X-1209252Y-137674D02*
Y-130945D01*
X-1280906D01*
Y-137467D01*
G01X-1283957Y-126024D02*
Y-98465D01*
G01Y-90591D02*
Y-63032D01*
G01Y-55157D02*
Y-27598D01*
G01X-1206201Y-2008D02*
Y46614D01*
X-1283957D01*
Y-19724D01*
G01X-1241950Y-184567D02*
X-1236950D01*
G01X-1206201Y-162000D02*
Y-184567D01*
X-1221161D01*
G01X-1153898Y-176000D02*
Y-225827D01*
X-1200748D01*
Y-162000D01*
G01X-1213467Y-176220D02*
X-1209252D01*
Y-147889D01*
G01X-1200748Y-156500D02*
Y-118346D01*
X-1153898D01*
G01X-1206201Y-116181D02*
Y-150630D01*
G01Y-80748D02*
Y-108307D01*
G01Y-45315D02*
Y-72874D01*
G01Y-9882D02*
Y-37441D01*
G01X-1185000Y-39000D02*
Y-42000D01*
G01Y-45000D02*
Y-48000D01*
G01X-1184800Y-27900D02*
Y-30900D01*
G01X-1184928Y-21950D02*
Y-24950D01*
G01X-1184800Y-36400D02*
Y-33400D01*
G01X-1184928Y-19750D02*
Y-16750D01*
G01X-1184850Y-10628D02*
Y-13628D01*
G01X-1184800Y-4300D02*
Y-7300D01*
G01Y-1500D02*
Y1500D01*
G01X-1153898Y-133500D02*
Y-168500D01*
G01Y-118346D02*
Y-126000D01*
G01X-1166000Y-37000D02*
Y-40000D01*
G01Y-51000D02*
Y-48000D01*
G01Y-45500D02*
Y-42500D01*
G01Y-34500D02*
Y-31500D01*
G01X-1165928Y-25450D02*
Y-28450D01*
G01Y-12250D02*
Y-9250D01*
G01Y-23250D02*
Y-20250D01*
G01Y-14750D02*
Y-17750D01*
G01Y-3950D02*
Y-6950D01*
G01X-1145079Y-148661D02*
Y-151024D01*
X-1136811D01*
G01X-1145079Y-109685D02*
Y-135669D01*
G01Y-71890D02*
Y-95118D01*
G01Y-35276D02*
Y-55354D01*
G01X-1081299Y2913D02*
Y40709D01*
X-1145079D01*
Y-15984D01*
G01X-1134843Y-132126D02*
Y-141378D01*
X-1128937D01*
G01X-1134843Y-120315D02*
Y-111063D01*
X-1130906D01*
G01X-1114828Y-176650D02*
X-1111828D01*
G01X-1106328D02*
X-1109328D01*
G01X-1089567Y-151024D02*
X-1081299D01*
Y-128976D01*
G01X-1091535Y-132126D02*
Y-137441D01*
X-1095472Y-141378D01*
G01X-1097441Y-111063D02*
X-1091535D01*
Y-120315D01*
G01X-1081299Y-116378D02*
Y-90394D01*
G01Y-75039D02*
Y-52992D01*
G01Y-35669D02*
Y-12441D01*
G01X-1030648Y-102205D02*
Y-195236D01*
X-1040688D01*
Y-312953D01*
X-1062538D01*
Y-195236D01*
X-1072578D01*
Y-157870D01*
G01Y-151240D02*
Y-116000D01*
G01Y-108500D02*
Y-102205D01*
X-1030648D01*
G01X-1065428Y-50850D02*
X-1062428D01*
G01X-1060400Y-35600D02*
X-1063400D01*
G01X-1060500Y-12000D02*
X-1063500D01*
G01X-1051228Y-51350D02*
Y-54350D01*
G01X-1048000Y-35500D02*
Y-32500D01*
G01Y-11500D02*
Y-8500D01*
G01X-1048100Y-18100D02*
Y-15100D01*
G01X-971378Y-118346D02*
Y-225827D01*
X-1018228D01*
Y-118346D01*
X-971378D01*
G01X-1019094Y-105824D02*
X-1025492D01*
Y-54879D01*
G01Y-47005D02*
Y-2714D01*
G01X-937894Y5160D02*
Y43782D01*
X-1025492D01*
Y5160D01*
G01X-1007500Y-470000D02*
X-1006450Y-475000D01*
X-1005250Y-470000D01*
X-1004050Y-475000D01*
X-1003000Y-470000D01*
G01X-1001125Y-475000D02*
X-999250Y-470000D01*
X-997375Y-475000D01*
G01X-998050Y-473250D02*
X-1000450D01*
G01X-994825Y-474333D02*
X-994225Y-474750D01*
X-993550Y-475000D01*
X-992950D01*
X-992350Y-474750D01*
X-991900Y-474333D01*
X-991675Y-473750D01*
X-991825Y-473167D01*
X-992200Y-472667D01*
X-992875Y-472333D01*
X-993775Y-472167D01*
X-994300Y-471833D01*
X-994525Y-471250D01*
X-994375Y-470667D01*
X-994000Y-470250D01*
X-993475Y-470000D01*
X-992950D01*
X-992425Y-470167D01*
X-991975Y-470583D01*
G01X-988825Y-475000D02*
Y-470000D01*
G01X-985675D02*
Y-475000D01*
G01Y-472500D02*
X-988825D01*
G01X-976525Y-474417D02*
X-976000Y-474833D01*
X-975400Y-475000D01*
X-974800Y-474833D01*
X-974275Y-474333D01*
X-973900Y-473583D01*
X-973750Y-472833D01*
Y-471917D01*
X-973900Y-471167D01*
X-974275Y-470500D01*
X-974725Y-470167D01*
X-975250Y-470000D01*
X-975850Y-470167D01*
X-976300Y-470500D01*
X-976600Y-471000D01*
X-976750Y-471667D01*
X-976600Y-472250D01*
X-976225Y-472833D01*
X-975775Y-473167D01*
X-975250Y-473250D01*
X-974650Y-473083D01*
X-974200Y-472667D01*
X-973750Y-471917D01*
G01X-969250Y-475000D02*
X-968725Y-474917D01*
X-968125Y-474667D01*
X-967750Y-474250D01*
X-967600Y-473667D01*
X-967750Y-473083D01*
X-968200Y-472583D01*
X-968875Y-472333D01*
X-969625D01*
X-970075Y-472167D01*
X-970450Y-471750D01*
X-970600Y-471167D01*
X-970375Y-470583D01*
X-969850Y-470167D01*
X-969250Y-470000D01*
X-968650Y-470167D01*
X-968125Y-470583D01*
X-967900Y-471167D01*
X-968050Y-471750D01*
X-968425Y-472167D01*
X-968875Y-472333D01*
X-969625D01*
X-970300Y-472583D01*
X-970750Y-473083D01*
X-970900Y-473667D01*
X-970750Y-474250D01*
X-970375Y-474667D01*
X-969775Y-474917D01*
X-969250Y-475000D01*
G01X-963250Y-470000D02*
X-963850Y-470167D01*
X-964300Y-470583D01*
X-964600Y-471083D01*
X-964825Y-471750D01*
X-964900Y-472500D01*
X-964825Y-473250D01*
X-964600Y-473917D01*
X-964300Y-474417D01*
X-963850Y-474833D01*
X-963250Y-475000D01*
X-962650Y-474833D01*
X-962200Y-474417D01*
X-961900Y-473917D01*
X-961675Y-473250D01*
X-961600Y-472500D01*
X-961675Y-471750D01*
X-961900Y-471083D01*
X-962200Y-470583D01*
X-962650Y-470167D01*
X-963250Y-470000D01*
G01X-958900Y-474250D02*
X-958450Y-474667D01*
X-957925Y-474917D01*
X-957250Y-475000D01*
X-956575Y-474833D01*
X-956050Y-474500D01*
X-955675Y-473917D01*
X-955600Y-473250D01*
X-955750Y-472583D01*
X-956125Y-472167D01*
X-956650Y-471833D01*
X-957175Y-471750D01*
X-957700Y-471833D01*
X-958375Y-472167D01*
X-958150Y-470000D01*
X-956125D01*
G01X-952675Y-470833D02*
X-952225Y-470333D01*
X-951700Y-470083D01*
X-951100Y-470000D01*
X-950350Y-470167D01*
X-949825Y-470583D01*
X-949675Y-471083D01*
X-949750Y-471583D01*
X-950050Y-472000D01*
X-951550Y-472833D01*
X-952225Y-473417D01*
X-952675Y-474250D01*
X-952825Y-475000D01*
X-949675D01*
G01X-946225Y-473333D02*
X-944275D01*
G01X-940675Y-472917D02*
X-940150Y-472333D01*
X-939700Y-472000D01*
X-939100Y-471833D01*
X-938575Y-472000D01*
X-938200Y-472333D01*
X-937900Y-472833D01*
X-937825Y-473417D01*
X-937900Y-473917D01*
X-938200Y-474417D01*
X-938650Y-474833D01*
X-939175Y-475000D01*
X-939775Y-474833D01*
X-940300Y-474333D01*
X-940600Y-473583D01*
X-940675Y-472750D01*
X-940525Y-471667D01*
X-940300Y-471083D01*
X-939925Y-470500D01*
X-939400Y-470083D01*
X-938875Y-470000D01*
X-938350Y-470167D01*
X-937975Y-470583D01*
G01X-934900Y-474000D02*
X-934450Y-474583D01*
X-933850Y-474917D01*
X-933175Y-475000D01*
X-932575Y-474917D01*
X-931975Y-474500D01*
X-931600Y-474000D01*
X-931525Y-473500D01*
X-931675Y-472917D01*
X-932200Y-472500D01*
X-932725Y-472333D01*
X-933400D01*
G01X-932725D02*
X-932275Y-472083D01*
X-931900Y-471667D01*
X-931750Y-471167D01*
X-931900Y-470667D01*
X-932275Y-470250D01*
X-932950Y-470000D01*
X-933625Y-470083D01*
X-934300Y-470417D01*
G01X-928525Y-474417D02*
X-928000Y-474833D01*
X-927400Y-475000D01*
X-926800Y-474833D01*
X-926275Y-474333D01*
X-925900Y-473583D01*
X-925750Y-472833D01*
Y-471917D01*
X-925900Y-471167D01*
X-926275Y-470500D01*
X-926725Y-470167D01*
X-927250Y-470000D01*
X-927850Y-470167D01*
X-928300Y-470500D01*
X-928600Y-471000D01*
X-928750Y-471667D01*
X-928600Y-472250D01*
X-928225Y-472833D01*
X-927775Y-473167D01*
X-927250Y-473250D01*
X-926650Y-473083D01*
X-926200Y-472667D01*
X-925750Y-471917D01*
G01X-922525Y-474417D02*
X-922000Y-474833D01*
X-921400Y-475000D01*
X-920800Y-474833D01*
X-920275Y-474333D01*
X-919900Y-473583D01*
X-919750Y-472833D01*
Y-471917D01*
X-919900Y-471167D01*
X-920275Y-470500D01*
X-920725Y-470167D01*
X-921250Y-470000D01*
X-921850Y-470167D01*
X-922300Y-470500D01*
X-922600Y-471000D01*
X-922750Y-471667D01*
X-922600Y-472250D01*
X-922225Y-472833D01*
X-921775Y-473167D01*
X-921250Y-473250D01*
X-920650Y-473083D01*
X-920200Y-472667D01*
X-919750Y-471917D01*
G01X-1006750Y-465000D02*
Y-460000D01*
X-1004875D01*
X-1004275Y-460250D01*
X-1003900Y-460583D01*
X-1003750Y-461250D01*
X-1003900Y-461917D01*
X-1004350Y-462333D01*
X-1004875Y-462583D01*
X-1006750D01*
G01X-1004875D02*
X-1003750Y-465000D01*
G01X-997750D02*
X-1000750D01*
Y-460000D01*
X-997750D01*
G01X-998950Y-462417D02*
X-1000750D01*
G01X-994900Y-465000D02*
Y-460000D01*
X-993400D01*
X-992800Y-460250D01*
X-992350Y-460583D01*
X-991975Y-461083D01*
X-991675Y-461667D01*
X-991600Y-462500D01*
X-991675Y-463333D01*
X-991975Y-463917D01*
X-992350Y-464417D01*
X-992800Y-464750D01*
X-993400Y-465000D01*
X-994900D01*
G01X-989200D02*
Y-460000D01*
X-987250Y-464167D01*
X-985300Y-460000D01*
Y-465000D01*
G01X-981250D02*
X-981850Y-464917D01*
X-982375Y-464583D01*
X-982825Y-464083D01*
X-983125Y-463500D01*
X-983275Y-462833D01*
Y-462167D01*
X-983125Y-461500D01*
X-982825Y-460917D01*
X-982375Y-460417D01*
X-981850Y-460083D01*
X-981250Y-460000D01*
X-980650Y-460083D01*
X-980125Y-460417D01*
X-979675Y-460917D01*
X-979375Y-461500D01*
X-979225Y-462167D01*
Y-462833D01*
X-979375Y-463500D01*
X-979675Y-464083D01*
X-980125Y-464583D01*
X-980650Y-464917D01*
X-981250Y-465000D01*
G01X-976975D02*
Y-460000D01*
X-973525Y-465000D01*
Y-460000D01*
G01X-970900Y-465000D02*
Y-460000D01*
X-969400D01*
X-968800Y-460250D01*
X-968350Y-460583D01*
X-967975Y-461083D01*
X-967675Y-461667D01*
X-967600Y-462500D01*
X-967675Y-463333D01*
X-967975Y-463917D01*
X-968350Y-464417D01*
X-968800Y-464750D01*
X-969400Y-465000D01*
X-970900D01*
G01X-1005250Y-455000D02*
Y-450000D01*
X-1006150Y-451000D01*
G01Y-455000D02*
X-1004350D01*
G01X-995200D02*
Y-450000D01*
X-993250Y-454167D01*
X-991300Y-450000D01*
Y-455000D01*
G01X-988150Y-450000D02*
X-986350D01*
G01X-987250D02*
Y-455000D01*
G01X-988150D02*
X-986350D01*
G01X-979600Y-450417D02*
X-980050Y-450167D01*
X-980575Y-450000D01*
X-981175D01*
X-981850Y-450250D01*
X-982375Y-450667D01*
X-982750Y-451167D01*
X-983050Y-452000D01*
X-983125Y-452750D01*
X-982975Y-453500D01*
X-982750Y-454000D01*
X-982300Y-454500D01*
X-981775Y-454833D01*
X-981250Y-455000D01*
X-980725D01*
X-980200Y-454833D01*
X-979750Y-454583D01*
X-979375Y-454250D01*
G01X-976750Y-455000D02*
Y-450000D01*
X-974875D01*
X-974275Y-450250D01*
X-973900Y-450583D01*
X-973750Y-451250D01*
X-973900Y-451917D01*
X-974350Y-452333D01*
X-974875Y-452583D01*
X-976750D01*
G01X-974875D02*
X-973750Y-455000D01*
G01X-969250D02*
X-969850Y-454917D01*
X-970375Y-454583D01*
X-970825Y-454083D01*
X-971125Y-453500D01*
X-971275Y-452833D01*
Y-452167D01*
X-971125Y-451500D01*
X-970825Y-450917D01*
X-970375Y-450417D01*
X-969850Y-450083D01*
X-969250Y-450000D01*
X-968650Y-450083D01*
X-968125Y-450417D01*
X-967675Y-450917D01*
X-967375Y-451500D01*
X-967225Y-452167D01*
Y-452833D01*
X-967375Y-453500D01*
X-967675Y-454083D01*
X-968125Y-454583D01*
X-968650Y-454917D01*
X-969250Y-455000D01*
G01X-964825Y-454333D02*
X-964225Y-454750D01*
X-963550Y-455000D01*
X-962950D01*
X-962350Y-454750D01*
X-961900Y-454333D01*
X-961675Y-453750D01*
X-961825Y-453167D01*
X-962200Y-452667D01*
X-962875Y-452333D01*
X-963775Y-452167D01*
X-964300Y-451833D01*
X-964525Y-451250D01*
X-964375Y-450667D01*
X-964000Y-450250D01*
X-963475Y-450000D01*
X-962950D01*
X-962425Y-450167D01*
X-961975Y-450583D01*
G01X-957250Y-455000D02*
X-957850Y-454917D01*
X-958375Y-454583D01*
X-958825Y-454083D01*
X-959125Y-453500D01*
X-959275Y-452833D01*
Y-452167D01*
X-959125Y-451500D01*
X-958825Y-450917D01*
X-958375Y-450417D01*
X-957850Y-450083D01*
X-957250Y-450000D01*
X-956650Y-450083D01*
X-956125Y-450417D01*
X-955675Y-450917D01*
X-955375Y-451500D01*
X-955225Y-452167D01*
Y-452833D01*
X-955375Y-453500D01*
X-955675Y-454083D01*
X-956125Y-454583D01*
X-956650Y-454917D01*
X-957250Y-455000D01*
G01X-952675D02*
Y-450000D01*
X-949825D01*
G01X-950875Y-452417D02*
X-952675D01*
G01X-945250Y-450000D02*
Y-455000D01*
G01X-946975Y-450000D02*
X-943525D01*
G01X-935500D02*
X-934450Y-455000D01*
X-933250Y-450000D01*
X-932050Y-455000D01*
X-931000Y-450000D01*
G01X-929125Y-455000D02*
X-927250Y-450000D01*
X-925375Y-455000D01*
G01X-926050Y-453250D02*
X-928450D01*
G01X-921250Y-455000D02*
Y-452750D01*
X-922750Y-450000D01*
G01X-919750D02*
X-921250Y-452750D01*
G01X-947000Y-173000D02*
X-950000D01*
G01X-950197Y-105824D02*
X-937894D01*
Y-54879D01*
G01Y-2714D02*
Y-47005D01*
G01X-887390Y-52350D02*
X-886857Y-52725D01*
X-886257Y-52950D01*
X-885723D01*
X-885190Y-52725D01*
X-884790Y-52350D01*
X-884590Y-51825D01*
X-884723Y-51300D01*
X-885057Y-50850D01*
X-885657Y-50550D01*
X-886457Y-50400D01*
X-886923Y-50100D01*
X-887123Y-49575D01*
X-886990Y-49050D01*
X-886657Y-48675D01*
X-886190Y-48450D01*
X-885723D01*
X-885257Y-48600D01*
X-884857Y-48975D01*
G01X-882090Y-53100D02*
X-879690Y-48450D01*
G01X-877323Y-52950D02*
Y-48450D01*
X-874257Y-52950D01*
Y-48450D01*
G01X-866923D02*
Y-52950D01*
X-864257D01*
G01X-859290D02*
Y-49950D01*
G01Y-50475D02*
X-859557Y-50175D01*
X-859957Y-50025D01*
X-860423Y-49950D01*
X-860890Y-50100D01*
X-861290Y-50400D01*
X-861557Y-50850D01*
X-861690Y-51450D01*
X-861557Y-52050D01*
X-861290Y-52500D01*
X-860890Y-52800D01*
X-860423Y-52950D01*
X-859957Y-52875D01*
X-859557Y-52650D01*
X-859290Y-52350D01*
G01X-856590Y-52950D02*
Y-48450D01*
G01Y-50700D02*
X-856257Y-50250D01*
X-855857Y-50025D01*
X-855457Y-49950D01*
X-854857Y-50100D01*
X-854457Y-50400D01*
X-854190Y-50925D01*
Y-51525D01*
X-854323Y-52125D01*
X-854590Y-52575D01*
X-855057Y-52875D01*
X-855457Y-52950D01*
X-855857Y-52875D01*
X-856257Y-52650D01*
X-856590Y-52275D01*
G01X-851290Y-50925D02*
X-849157D01*
X-849357Y-50400D01*
X-849690Y-50100D01*
X-850157Y-49950D01*
X-850623Y-50025D01*
X-851023Y-50250D01*
X-851290Y-50775D01*
X-851423Y-51225D01*
Y-51675D01*
X-851290Y-52125D01*
X-850957Y-52575D01*
X-850557Y-52875D01*
X-850090Y-52950D01*
X-849623Y-52800D01*
X-849157Y-52350D01*
G01X-845190Y-52950D02*
Y-48450D01*
G01X-814137Y-102391D02*
Y-110265D01*
X-806263D01*
G01X-814137Y-97667D02*
X-819649D01*
Y-85068D01*
X-814137D01*
G01X-806263Y-72470D02*
X-814137D01*
Y-80344D01*
G01X-800618Y-163819D02*
Y-169724D01*
X-794713D01*
G01Y-130354D02*
X-800618D01*
Y-136260D01*
G01X-788020Y-169724D02*
X-782114D01*
Y-163819D01*
G01Y-136260D02*
Y-130354D01*
X-788020D01*
G01X-784216Y-110265D02*
X-776342D01*
Y-102391D01*
G01Y-80344D02*
Y-72470D01*
X-784216D01*
G01X-671299Y-84882D02*
Y-225827D01*
X-749646D01*
Y-84882D01*
X-671299D01*
G01X-651200Y-122800D02*
X-648200D01*
G01X-627764Y-58790D02*
Y-184990D01*
X-585464D01*
Y-58790D01*
X-627764D01*
G01X-537000Y-124800D02*
X-534000D01*
G01X-465845Y-102205D02*
Y-195236D01*
X-475885D01*
Y-312953D01*
X-497735D01*
Y-195236D01*
X-507774D01*
Y-102205D01*
X-465845D01*
G01X-484921Y-18600D02*
X-487921D01*
G01X-465256Y-221299D02*
Y-105945D01*
X-418603D01*
Y-221299D01*
X-465256D01*
G01X-470971Y-20619D02*
Y-21119D01*
X-460971D01*
Y-10619D01*
G01X-461021Y-1500D02*
Y-1000D01*
X-471021D01*
Y-11500D01*
G01X-449628Y-83250D02*
X-446628D01*
G01X-447600Y-66400D02*
X-450600D01*
G01X-452921Y-19400D02*
X-455921D01*
G01X-436400Y-72600D02*
Y-75600D01*
G01Y-81100D02*
Y-78100D01*
G01Y-70100D02*
Y-67100D01*
G01Y-61600D02*
Y-64600D01*
G01Y-56100D02*
Y-59100D01*
G01Y-45100D02*
Y-48100D01*
G01Y-50600D02*
Y-53600D01*
G01Y-39600D02*
Y-42600D01*
G01Y-34100D02*
Y-37100D01*
G01Y-31000D02*
Y-28000D01*
G01X-440171Y-21519D02*
Y-22019D01*
X-430171D01*
Y-11519D01*
G01X-430221Y-2400D02*
Y-1900D01*
X-440221D01*
Y-12400D01*
G01X-413871Y-184580D02*
X-403871D01*
G01X-413881Y-176590D02*
Y-184590D01*
G01X-413878Y-168346D02*
Y-133898D01*
G01Y-126024D02*
Y-98465D01*
G01Y-90591D02*
Y-63032D01*
G01Y-55157D02*
Y-27598D01*
G01X-336122Y-2008D02*
Y46614D01*
X-413878D01*
Y-19724D01*
G01X-404611Y-176220D02*
X-410827D01*
Y-147647D01*
G01X-339173Y-137674D02*
Y-130945D01*
X-410827D01*
Y-137467D01*
G01X-371871Y-184567D02*
X-366871D01*
G01X-336122Y-162500D02*
Y-184567D01*
X-351083D01*
G01X-343389Y-176220D02*
X-339173D01*
Y-147889D01*
G01X-336122Y-116181D02*
Y-150630D01*
G01Y-80748D02*
Y-108307D01*
G01Y-45315D02*
Y-72874D01*
G01Y-9882D02*
Y-37441D01*
G01X-283819Y-176000D02*
Y-225827D01*
X-330669D01*
Y-162000D01*
G01Y-156500D02*
Y-118346D01*
X-283819D01*
G01X-315500Y-40500D02*
Y-43500D01*
G01Y-46000D02*
Y-49000D01*
G01X-315300Y-37900D02*
Y-34900D01*
G01X-315428Y-23450D02*
Y-26450D01*
G01X-315300Y-29400D02*
Y-32400D01*
G01X-315428Y-21250D02*
Y-18250D01*
G01X-315300Y-5800D02*
Y-8800D01*
G01X-315350Y-12128D02*
Y-15128D01*
G01X-315300Y-3000D02*
Y0D01*
G01X-296700Y-36500D02*
Y-39500D01*
G01Y-50300D02*
Y-47300D01*
G01Y-44800D02*
Y-41800D01*
G01Y-34000D02*
Y-31000D01*
G01X-296428Y-24450D02*
Y-27450D01*
G01Y-22250D02*
Y-19250D01*
G01X-296572Y-13750D02*
Y-16750D01*
G01Y-11250D02*
Y-8250D01*
G01X-296428Y-2950D02*
Y-5950D01*
G01X-283819Y-133500D02*
Y-168500D01*
G01X-275000Y-148661D02*
Y-151024D01*
X-266732D01*
G01X-275000Y-109685D02*
Y-135669D01*
G01X-283819Y-118346D02*
Y-126000D01*
G01X-275000Y-71890D02*
Y-95118D01*
G01Y-35276D02*
Y-55354D01*
G01X-211220Y2913D02*
Y40709D01*
X-275000D01*
Y-15984D01*
G01X-264764Y-132126D02*
Y-141378D01*
X-258858D01*
G01X-264764Y-120315D02*
Y-111063D01*
X-260827D01*
G01X-244750Y-176650D02*
X-241750D01*
G01X-236250D02*
X-239250D01*
G01X-221457Y-132126D02*
Y-137441D01*
X-225394Y-141378D01*
G01X-227362Y-111063D02*
X-221457D01*
Y-120315D01*
G01X-219488Y-151024D02*
X-211220D01*
Y-128976D01*
G01Y-116378D02*
Y-90394D01*
G01Y-75039D02*
Y-52992D01*
G01Y-35669D02*
Y-12441D01*
G01X-160570Y-102205D02*
Y-195236D01*
X-170609D01*
Y-312953D01*
X-192459D01*
Y-195236D01*
X-202499D01*
Y-157390D01*
G01Y-152410D02*
Y-116000D01*
G01Y-108500D02*
Y-102205D01*
X-160570D01*
G01X-193850Y-50350D02*
X-190850D01*
G01X-188600Y-35900D02*
X-191600D01*
G01X-188900Y-11300D02*
X-191900D01*
G01X-179650Y-50850D02*
Y-53850D01*
G01X-176400Y-35970D02*
Y-32970D01*
G01X-176500Y-11500D02*
Y-8500D01*
G01X-176300Y-18000D02*
Y-15000D01*
G01X-101299Y-118346D02*
Y-225827D01*
X-148150D01*
Y-118346D01*
X-101299D01*
G01X-149016Y-105824D02*
X-155413D01*
Y-54879D01*
G01Y-47005D02*
Y-2714D01*
G01X-67815Y5160D02*
Y43782D01*
X-155413D01*
Y5160D01*
G01X-76900Y-174000D02*
X-79900D01*
G01X-80118Y-105824D02*
X-67815D01*
Y-54879D01*
G01Y-2714D02*
Y-47005D01*
G54D16*
G01X-874510Y-499000D02*
Y-493000D01*
X-871290Y-499000D01*
Y-493000D01*
G01X-867200Y-499000D02*
X-867760Y-498900D01*
X-868250Y-498500D01*
X-868670Y-497900D01*
X-868950Y-497200D01*
X-869090Y-496400D01*
Y-495600D01*
X-868950Y-494800D01*
X-868670Y-494100D01*
X-868250Y-493500D01*
X-867760Y-493100D01*
X-867200Y-493000D01*
X-866640Y-493100D01*
X-866150Y-493500D01*
X-865730Y-494100D01*
X-865450Y-494800D01*
X-865310Y-495600D01*
Y-496400D01*
X-865450Y-497200D01*
X-865730Y-497900D01*
X-866150Y-498500D01*
X-866640Y-498900D01*
X-867200Y-499000D01*
G01X-861500Y-493000D02*
Y-499000D01*
G01X-863110Y-493000D02*
X-859890D01*
G01X-856640D02*
X-854960D01*
G01X-855800D02*
Y-499000D01*
G01X-856640D02*
X-854960D01*
G01X-848560Y-493500D02*
X-848980Y-493200D01*
X-849470Y-493000D01*
X-850030D01*
X-850660Y-493300D01*
X-851150Y-493800D01*
X-851500Y-494400D01*
X-851780Y-495400D01*
X-851850Y-496300D01*
X-851710Y-497200D01*
X-851500Y-497800D01*
X-851080Y-498400D01*
X-850590Y-498800D01*
X-850100Y-499000D01*
X-849610D01*
X-849120Y-498800D01*
X-848700Y-498500D01*
X-848350Y-498100D01*
G01X-843000Y-499000D02*
X-845800D01*
Y-493000D01*
X-843000D01*
G01X-844120Y-495900D02*
X-845800D01*
G01X-833000Y-499000D02*
X-833560Y-498900D01*
X-834050Y-498500D01*
X-834470Y-497900D01*
X-834750Y-497200D01*
X-834890Y-496400D01*
Y-495600D01*
X-834750Y-494800D01*
X-834470Y-494100D01*
X-834050Y-493500D01*
X-833560Y-493100D01*
X-833000Y-493000D01*
X-832440Y-493100D01*
X-831950Y-493500D01*
X-831530Y-494100D01*
X-831250Y-494800D01*
X-831110Y-495600D01*
Y-496400D01*
X-831250Y-497200D01*
X-831530Y-497900D01*
X-831950Y-498500D01*
X-832440Y-498900D01*
X-833000Y-499000D01*
G01X-828630D02*
Y-493000D01*
X-825970D01*
G01X-826950Y-495900D02*
X-828630D01*
G01X-817300Y-499000D02*
Y-493000D01*
X-815620D01*
X-815060Y-493300D01*
X-814640Y-494000D01*
X-814500Y-494800D01*
X-814640Y-495600D01*
X-814990Y-496200D01*
X-815620Y-496500D01*
X-817300D01*
G01X-811600Y-499000D02*
Y-493000D01*
X-809850D01*
X-809290Y-493300D01*
X-808940Y-493700D01*
X-808800Y-494500D01*
X-808940Y-495300D01*
X-809360Y-495800D01*
X-809850Y-496100D01*
X-811600D01*
G01X-809850D02*
X-808800Y-499000D01*
G01X-804500D02*
X-805060Y-498900D01*
X-805550Y-498500D01*
X-805970Y-497900D01*
X-806250Y-497200D01*
X-806390Y-496400D01*
Y-495600D01*
X-806250Y-494800D01*
X-805970Y-494100D01*
X-805550Y-493500D01*
X-805060Y-493100D01*
X-804500Y-493000D01*
X-803940Y-493100D01*
X-803450Y-493500D01*
X-803030Y-494100D01*
X-802750Y-494800D01*
X-802610Y-495600D01*
Y-496400D01*
X-802750Y-497200D01*
X-803030Y-497900D01*
X-803450Y-498500D01*
X-803940Y-498900D01*
X-804500Y-499000D01*
G01X-800200D02*
Y-493000D01*
X-798520D01*
X-797960Y-493300D01*
X-797540Y-494000D01*
X-797400Y-494800D01*
X-797540Y-495600D01*
X-797890Y-496200D01*
X-798520Y-496500D01*
X-800200D01*
G01X-794500Y-499000D02*
Y-493000D01*
X-792750D01*
X-792190Y-493300D01*
X-791840Y-493700D01*
X-791700Y-494500D01*
X-791840Y-495300D01*
X-792260Y-495800D01*
X-792750Y-496100D01*
X-794500D01*
G01X-792750D02*
X-791700Y-499000D01*
G01X-788240Y-493000D02*
X-786560D01*
G01X-787400D02*
Y-499000D01*
G01X-788240D02*
X-786560D01*
G01X-780300D02*
X-783100D01*
Y-493000D01*
X-780300D01*
G01X-781420Y-495900D02*
X-783100D01*
G01X-776000Y-493000D02*
Y-499000D01*
G01X-777610Y-493000D02*
X-774390D01*
G01X-772050Y-499000D02*
X-770300Y-493000D01*
X-768550Y-499000D01*
G01X-769180Y-496900D02*
X-771420D01*
G01X-766000Y-499000D02*
Y-493000D01*
X-764250D01*
X-763690Y-493300D01*
X-763340Y-493700D01*
X-763200Y-494500D01*
X-763340Y-495300D01*
X-763760Y-495800D01*
X-764250Y-496100D01*
X-766000D01*
G01X-764250D02*
X-763200Y-499000D01*
G01X-758900D02*
Y-496300D01*
X-760300Y-493000D01*
G01X-757500D02*
X-758900Y-496300D01*
G01X-748900Y-499000D02*
Y-493000D01*
X-747220D01*
X-746660Y-493300D01*
X-746240Y-494000D01*
X-746100Y-494800D01*
X-746240Y-495600D01*
X-746590Y-496200D01*
X-747220Y-496500D01*
X-748900D01*
G01X-743200Y-499000D02*
Y-493000D01*
X-741450D01*
X-740890Y-493300D01*
X-740540Y-493700D01*
X-740400Y-494500D01*
X-740540Y-495300D01*
X-740960Y-495800D01*
X-741450Y-496100D01*
X-743200D01*
G01X-741450D02*
X-740400Y-499000D01*
G01X-736100D02*
X-736660Y-498900D01*
X-737150Y-498500D01*
X-737570Y-497900D01*
X-737850Y-497200D01*
X-737990Y-496400D01*
Y-495600D01*
X-737850Y-494800D01*
X-737570Y-494100D01*
X-737150Y-493500D01*
X-736660Y-493100D01*
X-736100Y-493000D01*
X-735540Y-493100D01*
X-735050Y-493500D01*
X-734630Y-494100D01*
X-734350Y-494800D01*
X-734210Y-495600D01*
Y-496400D01*
X-734350Y-497200D01*
X-734630Y-497900D01*
X-735050Y-498500D01*
X-735540Y-498900D01*
X-736100Y-499000D01*
G01X-731800D02*
Y-493000D01*
X-730120D01*
X-729560Y-493300D01*
X-729140Y-494000D01*
X-729000Y-494800D01*
X-729140Y-495600D01*
X-729490Y-496200D01*
X-730120Y-496500D01*
X-731800D01*
G01X-723300Y-499000D02*
X-726100D01*
Y-493000D01*
X-723300D01*
G01X-724420Y-495900D02*
X-726100D01*
G01X-720400Y-499000D02*
Y-493000D01*
X-718650D01*
X-718090Y-493300D01*
X-717740Y-493700D01*
X-717600Y-494500D01*
X-717740Y-495300D01*
X-718160Y-495800D01*
X-718650Y-496100D01*
X-720400D01*
G01X-718650D02*
X-717600Y-499000D01*
G01X-713300Y-493000D02*
Y-499000D01*
G01X-714910Y-493000D02*
X-711690D01*
G01X-707600Y-499000D02*
Y-496300D01*
X-709000Y-493000D01*
G01X-706200D02*
X-707600Y-496300D01*
G01X-701900Y-499200D02*
X-702040Y-499100D01*
Y-498900D01*
X-701900Y-498800D01*
X-701760Y-498900D01*
Y-499100D01*
X-701900Y-499200D01*
G01Y-496500D02*
X-702040Y-496400D01*
Y-496200D01*
X-701900Y-496100D01*
X-701760Y-496200D01*
Y-496400D01*
X-701900Y-496500D01*
G54D17*
G01X-1189333Y-572500D02*
Y-565500D01*
X-1187667D01*
X-1187000Y-565850D01*
X-1186500Y-566317D01*
X-1186083Y-567017D01*
X-1185750Y-567833D01*
X-1185667Y-569000D01*
X-1185750Y-570167D01*
X-1186083Y-570983D01*
X-1186500Y-571684D01*
X-1187000Y-572150D01*
X-1187667Y-572500D01*
X-1189333D01*
G01X-1180700D02*
X-1181367Y-572383D01*
X-1181950Y-571917D01*
X-1182450Y-571217D01*
X-1182783Y-570400D01*
X-1182950Y-569467D01*
Y-568533D01*
X-1182783Y-567600D01*
X-1182450Y-566783D01*
X-1181950Y-566083D01*
X-1181367Y-565617D01*
X-1180700Y-565500D01*
X-1180033Y-565617D01*
X-1179450Y-566083D01*
X-1178950Y-566783D01*
X-1178617Y-567600D01*
X-1178450Y-568533D01*
Y-569467D01*
X-1178617Y-570400D01*
X-1178950Y-571217D01*
X-1179450Y-571917D01*
X-1180033Y-572383D01*
X-1180700Y-572500D01*
G01X-1172067Y-566083D02*
X-1172567Y-565733D01*
X-1173150Y-565500D01*
X-1173817D01*
X-1174567Y-565850D01*
X-1175150Y-566433D01*
X-1175567Y-567133D01*
X-1175900Y-568300D01*
X-1175983Y-569350D01*
X-1175817Y-570400D01*
X-1175567Y-571100D01*
X-1175067Y-571800D01*
X-1174483Y-572267D01*
X-1173900Y-572500D01*
X-1173317D01*
X-1172733Y-572267D01*
X-1172233Y-571917D01*
X-1171817Y-571450D01*
G01X-1168933Y-565500D02*
Y-570517D01*
X-1168600Y-571567D01*
X-1167933Y-572267D01*
X-1167100Y-572500D01*
X-1166267Y-572267D01*
X-1165600Y-571567D01*
X-1165267Y-570517D01*
Y-565500D01*
G01X-1162467Y-572500D02*
Y-565500D01*
X-1160300Y-571333D01*
X-1158133Y-565500D01*
Y-572500D01*
G01X-1151833D02*
X-1155167D01*
Y-565500D01*
X-1151833D01*
G01X-1153167Y-568883D02*
X-1155167D01*
G01X-1148617Y-572500D02*
Y-565500D01*
X-1144783Y-572500D01*
Y-565500D01*
G01X-1139900D02*
Y-572500D01*
G01X-1141817Y-565500D02*
X-1137983D01*
G01X-1128217Y-572500D02*
Y-565500D01*
X-1124383Y-572500D01*
Y-565500D01*
G01X-1121333D02*
Y-570517D01*
X-1121000Y-571567D01*
X-1120333Y-572267D01*
X-1119500Y-572500D01*
X-1118667Y-572267D01*
X-1118000Y-571567D01*
X-1117667Y-570517D01*
Y-565500D01*
G01X-1114867Y-572500D02*
Y-565500D01*
X-1112700Y-571333D01*
X-1110533Y-565500D01*
Y-572500D01*
G01X-1105233Y-568767D02*
X-1104900Y-568417D01*
X-1104650Y-567833D01*
X-1104483Y-567017D01*
X-1104650Y-566317D01*
X-1104983Y-565850D01*
X-1105567Y-565500D01*
X-1107817D01*
Y-572500D01*
X-1105067D01*
X-1104483Y-572033D01*
X-1104150Y-571333D01*
X-1103983Y-570517D01*
X-1104150Y-569700D01*
X-1104650Y-569000D01*
X-1105233Y-568767D01*
X-1107817D01*
G01X-1097433Y-572500D02*
X-1100767D01*
Y-565500D01*
X-1097433D01*
G01X-1098767Y-568883D02*
X-1100767D01*
G01X-1093967Y-572500D02*
Y-565500D01*
X-1091883D01*
X-1091217Y-565850D01*
X-1090800Y-566317D01*
X-1090633Y-567250D01*
X-1090800Y-568183D01*
X-1091300Y-568767D01*
X-1091883Y-569117D01*
X-1093967D01*
G01X-1091883D02*
X-1090633Y-572500D01*
G01X-1189250Y-531567D02*
X-1188583Y-532150D01*
X-1187833Y-532500D01*
X-1187167D01*
X-1186500Y-532150D01*
X-1186000Y-531567D01*
X-1185750Y-530750D01*
X-1185917Y-529933D01*
X-1186333Y-529233D01*
X-1187083Y-528767D01*
X-1188083Y-528533D01*
X-1188667Y-528067D01*
X-1188917Y-527250D01*
X-1188750Y-526433D01*
X-1188333Y-525850D01*
X-1187750Y-525500D01*
X-1187167D01*
X-1186583Y-525733D01*
X-1186083Y-526317D01*
G01X-1182450Y-532500D02*
Y-525500D01*
G01X-1178950D02*
Y-532500D01*
G01Y-529000D02*
X-1182450D01*
G01X-1172233Y-532500D02*
X-1175567D01*
Y-525500D01*
X-1172233D01*
G01X-1173567Y-528883D02*
X-1175567D01*
G01X-1165433Y-532500D02*
X-1168767D01*
Y-525500D01*
X-1165433D01*
G01X-1166767Y-528883D02*
X-1168767D01*
G01X-1160300Y-525500D02*
Y-532500D01*
G01X-1162217Y-525500D02*
X-1158383D01*
G01X-1146700D02*
Y-532500D01*
G01X-1148617Y-525500D02*
X-1144783D01*
G01X-1140900D02*
X-1138900D01*
G01X-1139900D02*
Y-532500D01*
G01X-1140900D02*
X-1138900D01*
G01X-1133100Y-525500D02*
Y-532500D01*
G01X-1135017Y-525500D02*
X-1131183D01*
G01X-1127967D02*
Y-532500D01*
X-1124633D01*
G01X-1117833D02*
X-1121167D01*
Y-525500D01*
X-1117833D01*
G01X-1119167Y-528883D02*
X-1121167D01*
G01X-1112700Y-532733D02*
X-1112867Y-532617D01*
Y-532383D01*
X-1112700Y-532267D01*
X-1112533Y-532383D01*
Y-532617D01*
X-1112700Y-532733D01*
G01Y-529584D02*
X-1112867Y-529467D01*
Y-529233D01*
X-1112700Y-529117D01*
X-1112533Y-529233D01*
Y-529467D01*
X-1112700Y-529584D01*
G01X-1187500Y-485500D02*
Y-492500D01*
G01X-1189417Y-485500D02*
X-1185583D01*
G01X-1181700D02*
X-1179700D01*
G01X-1180700D02*
Y-492500D01*
G01X-1181700D02*
X-1179700D01*
G01X-1173900Y-485500D02*
Y-492500D01*
G01X-1175817Y-485500D02*
X-1171983D01*
G01X-1168767D02*
Y-492500D01*
X-1165433D01*
G01X-1158633D02*
X-1161967D01*
Y-485500D01*
X-1158633D01*
G01X-1159967Y-488883D02*
X-1161967D01*
G01X-916667Y-570000D02*
Y-563000D01*
X-914583D01*
X-913917Y-563350D01*
X-913500Y-563817D01*
X-913333Y-564750D01*
X-913500Y-565683D01*
X-914000Y-566267D01*
X-914583Y-566617D01*
X-916667D01*
G01X-914583D02*
X-913333Y-570000D01*
G01X-906533D02*
X-909867D01*
Y-563000D01*
X-906533D01*
G01X-907867Y-566383D02*
X-909867D01*
G01X-903483Y-563000D02*
X-901400Y-570000D01*
X-899317Y-563000D01*
G01X-907850Y-451567D02*
X-907183Y-452150D01*
X-906433Y-452500D01*
X-905767D01*
X-905100Y-452150D01*
X-904600Y-451567D01*
X-904350Y-450750D01*
X-904517Y-449933D01*
X-904933Y-449233D01*
X-905683Y-448767D01*
X-906683Y-448533D01*
X-907267Y-448067D01*
X-907517Y-447250D01*
X-907350Y-446433D01*
X-906933Y-445850D01*
X-906350Y-445500D01*
X-905767D01*
X-905183Y-445733D01*
X-904683Y-446317D01*
G01X-897467Y-446083D02*
X-897967Y-445733D01*
X-898550Y-445500D01*
X-899217D01*
X-899967Y-445850D01*
X-900550Y-446433D01*
X-900967Y-447133D01*
X-901300Y-448300D01*
X-901383Y-449350D01*
X-901217Y-450400D01*
X-900967Y-451100D01*
X-900467Y-451800D01*
X-899883Y-452267D01*
X-899300Y-452500D01*
X-898717D01*
X-898133Y-452267D01*
X-897633Y-451917D01*
X-897217Y-451450D01*
G01X-894583Y-452500D02*
X-892500Y-445500D01*
X-890417Y-452500D01*
G01X-891167Y-450050D02*
X-893833D01*
G01X-887367Y-445500D02*
Y-452500D01*
X-884033D01*
G01X-877233D02*
X-880567D01*
Y-445500D01*
X-877233D01*
G01X-878567Y-448883D02*
X-880567D01*
G01X-874333Y-572500D02*
Y-565500D01*
X-872667D01*
X-872000Y-565850D01*
X-871500Y-566317D01*
X-871083Y-567017D01*
X-870750Y-567833D01*
X-870667Y-569000D01*
X-870750Y-570167D01*
X-871083Y-570983D01*
X-871500Y-571684D01*
X-872000Y-572150D01*
X-872667Y-572500D01*
X-874333D01*
G01X-866700Y-565500D02*
X-864700D01*
G01X-865700D02*
Y-572500D01*
G01X-866700D02*
X-864700D01*
G01X-860650Y-571567D02*
X-859983Y-572150D01*
X-859233Y-572500D01*
X-858567D01*
X-857900Y-572150D01*
X-857400Y-571567D01*
X-857150Y-570750D01*
X-857317Y-569933D01*
X-857733Y-569233D01*
X-858483Y-568767D01*
X-859483Y-568533D01*
X-860067Y-568067D01*
X-860317Y-567250D01*
X-860150Y-566433D01*
X-859733Y-565850D01*
X-859150Y-565500D01*
X-858567D01*
X-857983Y-565733D01*
X-857483Y-566317D01*
G01X-850267Y-566083D02*
X-850767Y-565733D01*
X-851350Y-565500D01*
X-852017D01*
X-852767Y-565850D01*
X-853350Y-566433D01*
X-853767Y-567133D01*
X-854100Y-568300D01*
X-854183Y-569350D01*
X-854017Y-570400D01*
X-853767Y-571100D01*
X-853267Y-571800D01*
X-852683Y-572267D01*
X-852100Y-572500D01*
X-851517D01*
X-850933Y-572267D01*
X-850433Y-571917D01*
X-850017Y-571450D01*
G01X-846967Y-565500D02*
Y-572500D01*
X-843633D01*
G01X-838500D02*
X-839167Y-572383D01*
X-839750Y-571917D01*
X-840250Y-571217D01*
X-840583Y-570400D01*
X-840750Y-569467D01*
Y-568533D01*
X-840583Y-567600D01*
X-840250Y-566783D01*
X-839750Y-566083D01*
X-839167Y-565617D01*
X-838500Y-565500D01*
X-837833Y-565617D01*
X-837250Y-566083D01*
X-836750Y-566783D01*
X-836417Y-567600D01*
X-836250Y-568533D01*
Y-569467D01*
X-836417Y-570400D01*
X-836750Y-571217D01*
X-837250Y-571917D01*
X-837833Y-572383D01*
X-838500Y-572500D01*
G01X-833450Y-571567D02*
X-832783Y-572150D01*
X-832033Y-572500D01*
X-831367D01*
X-830700Y-572150D01*
X-830200Y-571567D01*
X-829950Y-570750D01*
X-830117Y-569933D01*
X-830533Y-569233D01*
X-831283Y-568767D01*
X-832283Y-568533D01*
X-832867Y-568067D01*
X-833117Y-567250D01*
X-832950Y-566433D01*
X-832533Y-565850D01*
X-831950Y-565500D01*
X-831367D01*
X-830783Y-565733D01*
X-830283Y-566317D01*
G01X-823233Y-572500D02*
X-826567D01*
Y-565500D01*
X-823233D01*
G01X-824567Y-568883D02*
X-826567D01*
G01X-819933Y-572500D02*
Y-565500D01*
X-818267D01*
X-817600Y-565850D01*
X-817100Y-566317D01*
X-816683Y-567017D01*
X-816350Y-567833D01*
X-816267Y-569000D01*
X-816350Y-570167D01*
X-816683Y-570983D01*
X-817100Y-571684D01*
X-817600Y-572150D01*
X-818267Y-572500D01*
X-819933D01*
G01X-807000Y-565500D02*
X-805833Y-572500D01*
X-804500Y-565500D01*
X-803167Y-572500D01*
X-802000Y-565500D01*
G01X-798700D02*
X-796700D01*
G01X-797700D02*
Y-572500D01*
G01X-798700D02*
X-796700D01*
G01X-790900Y-565500D02*
Y-572500D01*
G01X-792817Y-565500D02*
X-788983D01*
G01X-785850Y-572500D02*
Y-565500D01*
G01X-782350D02*
Y-572500D01*
G01Y-569000D02*
X-785850D01*
G01X-777300Y-572500D02*
X-777967Y-572383D01*
X-778550Y-571917D01*
X-779050Y-571217D01*
X-779383Y-570400D01*
X-779550Y-569467D01*
Y-568533D01*
X-779383Y-567600D01*
X-779050Y-566783D01*
X-778550Y-566083D01*
X-777967Y-565617D01*
X-777300Y-565500D01*
X-776633Y-565617D01*
X-776050Y-566083D01*
X-775550Y-566783D01*
X-775217Y-567600D01*
X-775050Y-568533D01*
Y-569467D01*
X-775217Y-570400D01*
X-775550Y-571217D01*
X-776050Y-571917D01*
X-776633Y-572383D01*
X-777300Y-572500D01*
G01X-772333Y-565500D02*
Y-570517D01*
X-772000Y-571567D01*
X-771333Y-572267D01*
X-770500Y-572500D01*
X-769667Y-572267D01*
X-769000Y-571567D01*
X-768667Y-570517D01*
Y-565500D01*
G01X-763700D02*
Y-572500D01*
G01X-765617Y-565500D02*
X-761783D01*
G01X-750100D02*
Y-572500D01*
G01X-752017Y-565500D02*
X-748183D01*
G01X-745050Y-572500D02*
Y-565500D01*
G01X-741550D02*
Y-572500D01*
G01Y-569000D02*
X-745050D01*
G01X-734833Y-572500D02*
X-738167D01*
Y-565500D01*
X-734833D01*
G01X-736167Y-568883D02*
X-738167D01*
G01X-724567Y-572500D02*
Y-565500D01*
X-722567D01*
X-721900Y-565850D01*
X-721400Y-566667D01*
X-721233Y-567600D01*
X-721400Y-568533D01*
X-721817Y-569233D01*
X-722567Y-569584D01*
X-724567D01*
G01X-717767Y-572500D02*
Y-565500D01*
X-715683D01*
X-715017Y-565850D01*
X-714600Y-566317D01*
X-714433Y-567250D01*
X-714600Y-568183D01*
X-715100Y-568767D01*
X-715683Y-569117D01*
X-717767D01*
G01X-715683D02*
X-714433Y-572500D01*
G01X-710300Y-565500D02*
X-708300D01*
G01X-709300D02*
Y-572500D01*
G01X-710300D02*
X-708300D01*
G01X-702500D02*
X-703167Y-572383D01*
X-703750Y-571917D01*
X-704250Y-571217D01*
X-704583Y-570400D01*
X-704750Y-569467D01*
Y-568533D01*
X-704583Y-567600D01*
X-704250Y-566783D01*
X-703750Y-566083D01*
X-703167Y-565617D01*
X-702500Y-565500D01*
X-701833Y-565617D01*
X-701250Y-566083D01*
X-700750Y-566783D01*
X-700417Y-567600D01*
X-700250Y-568533D01*
Y-569467D01*
X-700417Y-570400D01*
X-700750Y-571217D01*
X-701250Y-571917D01*
X-701833Y-572383D01*
X-702500Y-572500D01*
G01X-697367D02*
Y-565500D01*
X-695283D01*
X-694617Y-565850D01*
X-694200Y-566317D01*
X-694033Y-567250D01*
X-694200Y-568183D01*
X-694700Y-568767D01*
X-695283Y-569117D01*
X-697367D01*
G01X-695283D02*
X-694033Y-572500D01*
G01X-684600Y-565500D02*
X-683433Y-572500D01*
X-682100Y-565500D01*
X-680767Y-572500D01*
X-679600Y-565500D01*
G01X-676967Y-572500D02*
Y-565500D01*
X-674883D01*
X-674217Y-565850D01*
X-673800Y-566317D01*
X-673633Y-567250D01*
X-673800Y-568183D01*
X-674300Y-568767D01*
X-674883Y-569117D01*
X-676967D01*
G01X-674883D02*
X-673633Y-572500D01*
G01X-669500Y-565500D02*
X-667500D01*
G01X-668500D02*
Y-572500D01*
G01X-669500D02*
X-667500D01*
G01X-661700Y-565500D02*
Y-572500D01*
G01X-663617Y-565500D02*
X-659783D01*
G01X-654900D02*
Y-572500D01*
G01X-656817Y-565500D02*
X-652983D01*
G01X-646433Y-572500D02*
X-649767D01*
Y-565500D01*
X-646433D01*
G01X-647767Y-568883D02*
X-649767D01*
G01X-643217Y-572500D02*
Y-565500D01*
X-639383Y-572500D01*
Y-565500D01*
G01X-625867Y-566083D02*
X-626367Y-565733D01*
X-626950Y-565500D01*
X-627617D01*
X-628367Y-565850D01*
X-628950Y-566433D01*
X-629367Y-567133D01*
X-629700Y-568300D01*
X-629783Y-569350D01*
X-629617Y-570400D01*
X-629367Y-571100D01*
X-628867Y-571800D01*
X-628283Y-572267D01*
X-627700Y-572500D01*
X-627117D01*
X-626533Y-572267D01*
X-626033Y-571917D01*
X-625617Y-571450D01*
G01X-620900Y-572500D02*
X-621567Y-572383D01*
X-622150Y-571917D01*
X-622650Y-571217D01*
X-622983Y-570400D01*
X-623150Y-569467D01*
Y-568533D01*
X-622983Y-567600D01*
X-622650Y-566783D01*
X-622150Y-566083D01*
X-621567Y-565617D01*
X-620900Y-565500D01*
X-620233Y-565617D01*
X-619650Y-566083D01*
X-619150Y-566783D01*
X-618817Y-567600D01*
X-618650Y-568533D01*
Y-569467D01*
X-618817Y-570400D01*
X-619150Y-571217D01*
X-619650Y-571917D01*
X-620233Y-572383D01*
X-620900Y-572500D01*
G01X-616017D02*
Y-565500D01*
X-612183Y-572500D01*
Y-565500D01*
G01X-609050Y-571567D02*
X-608383Y-572150D01*
X-607633Y-572500D01*
X-606967D01*
X-606300Y-572150D01*
X-605800Y-571567D01*
X-605550Y-570750D01*
X-605717Y-569933D01*
X-606133Y-569233D01*
X-606883Y-568767D01*
X-607883Y-568533D01*
X-608467Y-568067D01*
X-608717Y-567250D01*
X-608550Y-566433D01*
X-608133Y-565850D01*
X-607550Y-565500D01*
X-606967D01*
X-606383Y-565733D01*
X-605883Y-566317D01*
G01X-598833Y-572500D02*
X-602167D01*
Y-565500D01*
X-598833D01*
G01X-600167Y-568883D02*
X-602167D01*
G01X-595617Y-572500D02*
Y-565500D01*
X-591783Y-572500D01*
Y-565500D01*
G01X-586900D02*
Y-572500D01*
G01X-588817Y-565500D02*
X-584983D01*
G01X-872500Y-587500D02*
X-873167Y-587383D01*
X-873750Y-586917D01*
X-874250Y-586217D01*
X-874583Y-585400D01*
X-874750Y-584467D01*
Y-583533D01*
X-874583Y-582600D01*
X-874250Y-581783D01*
X-873750Y-581083D01*
X-873167Y-580617D01*
X-872500Y-580500D01*
X-871833Y-580617D01*
X-871250Y-581083D01*
X-870750Y-581783D01*
X-870417Y-582600D01*
X-870250Y-583533D01*
Y-584467D01*
X-870417Y-585400D01*
X-870750Y-586217D01*
X-871250Y-586917D01*
X-871833Y-587383D01*
X-872500Y-587500D01*
G01X-867283D02*
Y-580500D01*
X-864117D01*
G01X-865283Y-583883D02*
X-867283D01*
G01X-854267Y-587500D02*
Y-580500D01*
X-852100Y-586333D01*
X-849933Y-580500D01*
Y-587500D01*
G01X-846300Y-580500D02*
X-844300D01*
G01X-845300D02*
Y-587500D01*
G01X-846300D02*
X-844300D01*
G01X-836667Y-581083D02*
X-837167Y-580733D01*
X-837750Y-580500D01*
X-838417D01*
X-839167Y-580850D01*
X-839750Y-581433D01*
X-840167Y-582133D01*
X-840500Y-583300D01*
X-840583Y-584350D01*
X-840417Y-585400D01*
X-840167Y-586100D01*
X-839667Y-586800D01*
X-839083Y-587267D01*
X-838500Y-587500D01*
X-837917D01*
X-837333Y-587267D01*
X-836833Y-586917D01*
X-836417Y-586450D01*
G01X-833367Y-587500D02*
Y-580500D01*
X-831283D01*
X-830617Y-580850D01*
X-830200Y-581317D01*
X-830033Y-582250D01*
X-830200Y-583183D01*
X-830700Y-583767D01*
X-831283Y-584117D01*
X-833367D01*
G01X-831283D02*
X-830033Y-587500D01*
G01X-824900D02*
X-825567Y-587383D01*
X-826150Y-586917D01*
X-826650Y-586217D01*
X-826983Y-585400D01*
X-827150Y-584467D01*
Y-583533D01*
X-826983Y-582600D01*
X-826650Y-581783D01*
X-826150Y-581083D01*
X-825567Y-580617D01*
X-824900Y-580500D01*
X-824233Y-580617D01*
X-823650Y-581083D01*
X-823150Y-581783D01*
X-822817Y-582600D01*
X-822650Y-583533D01*
Y-584467D01*
X-822817Y-585400D01*
X-823150Y-586217D01*
X-823650Y-586917D01*
X-824233Y-587383D01*
X-824900Y-587500D01*
G01X-819850Y-586567D02*
X-819183Y-587150D01*
X-818433Y-587500D01*
X-817767D01*
X-817100Y-587150D01*
X-816600Y-586567D01*
X-816350Y-585750D01*
X-816517Y-584933D01*
X-816933Y-584233D01*
X-817683Y-583767D01*
X-818683Y-583533D01*
X-819267Y-583067D01*
X-819517Y-582250D01*
X-819350Y-581433D01*
X-818933Y-580850D01*
X-818350Y-580500D01*
X-817767D01*
X-817183Y-580733D01*
X-816683Y-581317D01*
G01X-811300Y-587500D02*
X-811967Y-587383D01*
X-812550Y-586917D01*
X-813050Y-586217D01*
X-813383Y-585400D01*
X-813550Y-584467D01*
Y-583533D01*
X-813383Y-582600D01*
X-813050Y-581783D01*
X-812550Y-581083D01*
X-811967Y-580617D01*
X-811300Y-580500D01*
X-810633Y-580617D01*
X-810050Y-581083D01*
X-809550Y-581783D01*
X-809217Y-582600D01*
X-809050Y-583533D01*
Y-584467D01*
X-809217Y-585400D01*
X-809550Y-586217D01*
X-810050Y-586917D01*
X-810633Y-587383D01*
X-811300Y-587500D01*
G01X-806083D02*
Y-580500D01*
X-802917D01*
G01X-804083Y-583883D02*
X-806083D01*
G01X-797700Y-580500D02*
Y-587500D01*
G01X-799617Y-580500D02*
X-795783D01*
G01X-782267Y-581083D02*
X-782767Y-580733D01*
X-783350Y-580500D01*
X-784017D01*
X-784767Y-580850D01*
X-785350Y-581433D01*
X-785767Y-582133D01*
X-786100Y-583300D01*
X-786183Y-584350D01*
X-786017Y-585400D01*
X-785767Y-586100D01*
X-785267Y-586800D01*
X-784683Y-587267D01*
X-784100Y-587500D01*
X-783517D01*
X-782933Y-587267D01*
X-782433Y-586917D01*
X-782017Y-586450D01*
G01X-777300Y-587500D02*
X-777967Y-587383D01*
X-778550Y-586917D01*
X-779050Y-586217D01*
X-779383Y-585400D01*
X-779550Y-584467D01*
Y-583533D01*
X-779383Y-582600D01*
X-779050Y-581783D01*
X-778550Y-581083D01*
X-777967Y-580617D01*
X-777300Y-580500D01*
X-776633Y-580617D01*
X-776050Y-581083D01*
X-775550Y-581783D01*
X-775217Y-582600D01*
X-775050Y-583533D01*
Y-584467D01*
X-775217Y-585400D01*
X-775550Y-586217D01*
X-776050Y-586917D01*
X-776633Y-587383D01*
X-777300Y-587500D01*
G01X-772167D02*
Y-580500D01*
X-770083D01*
X-769417Y-580850D01*
X-769000Y-581317D01*
X-768833Y-582250D01*
X-769000Y-583183D01*
X-769500Y-583767D01*
X-770083Y-584117D01*
X-772167D01*
G01X-770083D02*
X-768833Y-587500D01*
G01X-765367D02*
Y-580500D01*
X-763367D01*
X-762700Y-580850D01*
X-762200Y-581667D01*
X-762033Y-582600D01*
X-762200Y-583533D01*
X-762617Y-584233D01*
X-763367Y-584584D01*
X-765367D01*
G01X-756900Y-587500D02*
X-757567Y-587383D01*
X-758150Y-586917D01*
X-758650Y-586217D01*
X-758983Y-585400D01*
X-759150Y-584467D01*
Y-583533D01*
X-758983Y-582600D01*
X-758650Y-581783D01*
X-758150Y-581083D01*
X-757567Y-580617D01*
X-756900Y-580500D01*
X-756233Y-580617D01*
X-755650Y-581083D01*
X-755150Y-581783D01*
X-754817Y-582600D01*
X-754650Y-583533D01*
Y-584467D01*
X-754817Y-585400D01*
X-755150Y-586217D01*
X-755650Y-586917D01*
X-756233Y-587383D01*
X-756900Y-587500D01*
G01X-751767D02*
Y-580500D01*
X-749683D01*
X-749017Y-580850D01*
X-748600Y-581317D01*
X-748433Y-582250D01*
X-748600Y-583183D01*
X-749100Y-583767D01*
X-749683Y-584117D01*
X-751767D01*
G01X-749683D02*
X-748433Y-587500D01*
G01X-745383D02*
X-743300Y-580500D01*
X-741217Y-587500D01*
G01X-741967Y-585050D02*
X-744633D01*
G01X-736500Y-580500D02*
Y-587500D01*
G01X-738417Y-580500D02*
X-734583D01*
G01X-730700D02*
X-728700D01*
G01X-729700D02*
Y-587500D01*
G01X-730700D02*
X-728700D01*
G01X-722900D02*
X-723567Y-587383D01*
X-724150Y-586917D01*
X-724650Y-586217D01*
X-724983Y-585400D01*
X-725150Y-584467D01*
Y-583533D01*
X-724983Y-582600D01*
X-724650Y-581783D01*
X-724150Y-581083D01*
X-723567Y-580617D01*
X-722900Y-580500D01*
X-722233Y-580617D01*
X-721650Y-581083D01*
X-721150Y-581783D01*
X-720817Y-582600D01*
X-720650Y-583533D01*
Y-584467D01*
X-720817Y-585400D01*
X-721150Y-586217D01*
X-721650Y-586917D01*
X-722233Y-587383D01*
X-722900Y-587500D01*
G01X-718017D02*
Y-580500D01*
X-714183Y-587500D01*
Y-580500D01*
G01X-709300Y-587733D02*
X-709467Y-587617D01*
Y-587383D01*
X-709300Y-587267D01*
X-709133Y-587383D01*
Y-587617D01*
X-709300Y-587733D01*
G01X-870667Y-551083D02*
X-871167Y-550733D01*
X-871750Y-550500D01*
X-872417D01*
X-873167Y-550850D01*
X-873750Y-551433D01*
X-874167Y-552133D01*
X-874500Y-553300D01*
X-874583Y-554350D01*
X-874417Y-555400D01*
X-874167Y-556100D01*
X-873667Y-556800D01*
X-873083Y-557267D01*
X-872500Y-557500D01*
X-871917D01*
X-871333Y-557267D01*
X-870833Y-556917D01*
X-870417Y-556450D01*
G01X-865700Y-557500D02*
X-866367Y-557383D01*
X-866950Y-556917D01*
X-867450Y-556217D01*
X-867783Y-555400D01*
X-867950Y-554467D01*
Y-553533D01*
X-867783Y-552600D01*
X-867450Y-551783D01*
X-866950Y-551083D01*
X-866367Y-550617D01*
X-865700Y-550500D01*
X-865033Y-550617D01*
X-864450Y-551083D01*
X-863950Y-551783D01*
X-863617Y-552600D01*
X-863450Y-553533D01*
Y-554467D01*
X-863617Y-555400D01*
X-863950Y-556217D01*
X-864450Y-556917D01*
X-865033Y-557383D01*
X-865700Y-557500D01*
G01X-860817D02*
Y-550500D01*
X-856983Y-557500D01*
Y-550500D01*
G01X-853683Y-557500D02*
Y-550500D01*
X-850517D01*
G01X-851683Y-553883D02*
X-853683D01*
G01X-846300Y-550500D02*
X-844300D01*
G01X-845300D02*
Y-557500D01*
G01X-846300D02*
X-844300D01*
G01X-840333D02*
Y-550500D01*
X-838667D01*
X-838000Y-550850D01*
X-837500Y-551317D01*
X-837083Y-552017D01*
X-836750Y-552833D01*
X-836667Y-554000D01*
X-836750Y-555167D01*
X-837083Y-555983D01*
X-837500Y-556684D01*
X-838000Y-557150D01*
X-838667Y-557500D01*
X-840333D01*
G01X-830033D02*
X-833367D01*
Y-550500D01*
X-830033D01*
G01X-831367Y-553883D02*
X-833367D01*
G01X-826817Y-557500D02*
Y-550500D01*
X-822983Y-557500D01*
Y-550500D01*
G01X-816267Y-551083D02*
X-816767Y-550733D01*
X-817350Y-550500D01*
X-818017D01*
X-818767Y-550850D01*
X-819350Y-551433D01*
X-819767Y-552133D01*
X-820100Y-553300D01*
X-820183Y-554350D01*
X-820017Y-555400D01*
X-819767Y-556100D01*
X-819267Y-556800D01*
X-818683Y-557267D01*
X-818100Y-557500D01*
X-817517D01*
X-816933Y-557267D01*
X-816433Y-556917D01*
X-816017Y-556450D01*
G01X-809633Y-557500D02*
X-812967D01*
Y-550500D01*
X-809633D01*
G01X-810967Y-553883D02*
X-812967D01*
G01X-799783Y-557500D02*
X-797700Y-550500D01*
X-795617Y-557500D01*
G01X-796367Y-555050D02*
X-799033D01*
G01X-792817Y-557500D02*
Y-550500D01*
X-788983Y-557500D01*
Y-550500D01*
G01X-785933Y-557500D02*
Y-550500D01*
X-784267D01*
X-783600Y-550850D01*
X-783100Y-551317D01*
X-782683Y-552017D01*
X-782350Y-552833D01*
X-782267Y-554000D01*
X-782350Y-555167D01*
X-782683Y-555983D01*
X-783100Y-556684D01*
X-783600Y-557150D01*
X-784267Y-557500D01*
X-785933D01*
G01X-771500Y-550500D02*
X-769500D01*
G01X-770500D02*
Y-557500D01*
G01X-771500D02*
X-769500D01*
G01X-763700Y-550500D02*
Y-557500D01*
G01X-765617Y-550500D02*
X-761783D01*
G01X-758650Y-556567D02*
X-757983Y-557150D01*
X-757233Y-557500D01*
X-756567D01*
X-755900Y-557150D01*
X-755400Y-556567D01*
X-755150Y-555750D01*
X-755317Y-554933D01*
X-755733Y-554233D01*
X-756483Y-553767D01*
X-757483Y-553533D01*
X-758067Y-553067D01*
X-758317Y-552250D01*
X-758150Y-551433D01*
X-757733Y-550850D01*
X-757150Y-550500D01*
X-756567D01*
X-755983Y-550733D01*
X-755483Y-551317D01*
G01X-741467Y-551083D02*
X-741967Y-550733D01*
X-742550Y-550500D01*
X-743217D01*
X-743967Y-550850D01*
X-744550Y-551433D01*
X-744967Y-552133D01*
X-745300Y-553300D01*
X-745383Y-554350D01*
X-745217Y-555400D01*
X-744967Y-556100D01*
X-744467Y-556800D01*
X-743883Y-557267D01*
X-743300Y-557500D01*
X-742717D01*
X-742133Y-557267D01*
X-741633Y-556917D01*
X-741217Y-556450D01*
G01X-736500Y-557500D02*
X-737167Y-557383D01*
X-737750Y-556917D01*
X-738250Y-556217D01*
X-738583Y-555400D01*
X-738750Y-554467D01*
Y-553533D01*
X-738583Y-552600D01*
X-738250Y-551783D01*
X-737750Y-551083D01*
X-737167Y-550617D01*
X-736500Y-550500D01*
X-735833Y-550617D01*
X-735250Y-551083D01*
X-734750Y-551783D01*
X-734417Y-552600D01*
X-734250Y-553533D01*
Y-554467D01*
X-734417Y-555400D01*
X-734750Y-556217D01*
X-735250Y-556917D01*
X-735833Y-557383D01*
X-736500Y-557500D01*
G01X-731617D02*
Y-550500D01*
X-727783Y-557500D01*
Y-550500D01*
G01X-722900D02*
Y-557500D01*
G01X-724817Y-550500D02*
X-720983D01*
G01X-714433Y-557500D02*
X-717767D01*
Y-550500D01*
X-714433D01*
G01X-715767Y-553883D02*
X-717767D01*
G01X-711217Y-557500D02*
Y-550500D01*
X-707383Y-557500D01*
Y-550500D01*
G01X-702500D02*
Y-557500D01*
G01X-704417Y-550500D02*
X-700583D01*
G01X-697450Y-556567D02*
X-696783Y-557150D01*
X-696033Y-557500D01*
X-695367D01*
X-694700Y-557150D01*
X-694200Y-556567D01*
X-693950Y-555750D01*
X-694117Y-554933D01*
X-694533Y-554233D01*
X-695283Y-553767D01*
X-696283Y-553533D01*
X-696867Y-553067D01*
X-697117Y-552250D01*
X-696950Y-551433D01*
X-696533Y-550850D01*
X-695950Y-550500D01*
X-695367D01*
X-694783Y-550733D01*
X-694283Y-551317D01*
G01X-684267Y-557500D02*
Y-550500D01*
X-682100Y-556333D01*
X-679933Y-550500D01*
Y-557500D01*
G01X-677383D02*
X-675300Y-550500D01*
X-673217Y-557500D01*
G01X-673967Y-555050D02*
X-676633D01*
G01X-668500Y-557500D02*
Y-554350D01*
X-670167Y-550500D01*
G01X-666833D02*
X-668500Y-554350D01*
G01X-656817Y-557500D02*
Y-550500D01*
X-652983Y-557500D01*
Y-550500D01*
G01X-648100Y-557500D02*
X-648767Y-557383D01*
X-649350Y-556917D01*
X-649850Y-556217D01*
X-650183Y-555400D01*
X-650350Y-554467D01*
Y-553533D01*
X-650183Y-552600D01*
X-649850Y-551783D01*
X-649350Y-551083D01*
X-648767Y-550617D01*
X-648100Y-550500D01*
X-647433Y-550617D01*
X-646850Y-551083D01*
X-646350Y-551783D01*
X-646017Y-552600D01*
X-645850Y-553533D01*
Y-554467D01*
X-646017Y-555400D01*
X-646350Y-556217D01*
X-646850Y-556917D01*
X-647433Y-557383D01*
X-648100Y-557500D01*
G01X-641300Y-550500D02*
Y-557500D01*
G01X-643217Y-550500D02*
X-639383D01*
G01X-627033Y-553767D02*
X-626700Y-553417D01*
X-626450Y-552833D01*
X-626283Y-552017D01*
X-626450Y-551317D01*
X-626783Y-550850D01*
X-627367Y-550500D01*
X-629617D01*
Y-557500D01*
X-626867D01*
X-626283Y-557033D01*
X-625950Y-556333D01*
X-625783Y-555517D01*
X-625950Y-554700D01*
X-626450Y-554000D01*
X-627033Y-553767D01*
X-629617D01*
G01X-619233Y-557500D02*
X-622567D01*
Y-550500D01*
X-619233D01*
G01X-620567Y-553883D02*
X-622567D01*
G01X-870667Y-536083D02*
X-871167Y-535733D01*
X-871750Y-535500D01*
X-872417D01*
X-873167Y-535850D01*
X-873750Y-536433D01*
X-874167Y-537133D01*
X-874500Y-538300D01*
X-874583Y-539350D01*
X-874417Y-540400D01*
X-874167Y-541100D01*
X-873667Y-541800D01*
X-873083Y-542267D01*
X-872500Y-542500D01*
X-871917D01*
X-871333Y-542267D01*
X-870833Y-541917D01*
X-870417Y-541450D01*
G01X-865700Y-542500D02*
X-866367Y-542383D01*
X-866950Y-541917D01*
X-867450Y-541217D01*
X-867783Y-540400D01*
X-867950Y-539467D01*
Y-538533D01*
X-867783Y-537600D01*
X-867450Y-536783D01*
X-866950Y-536083D01*
X-866367Y-535617D01*
X-865700Y-535500D01*
X-865033Y-535617D01*
X-864450Y-536083D01*
X-863950Y-536783D01*
X-863617Y-537600D01*
X-863450Y-538533D01*
Y-539467D01*
X-863617Y-540400D01*
X-863950Y-541217D01*
X-864450Y-541917D01*
X-865033Y-542383D01*
X-865700Y-542500D01*
G01X-860567D02*
Y-535500D01*
X-858483D01*
X-857817Y-535850D01*
X-857400Y-536317D01*
X-857233Y-537250D01*
X-857400Y-538183D01*
X-857900Y-538767D01*
X-858483Y-539117D01*
X-860567D01*
G01X-858483D02*
X-857233Y-542500D01*
G01X-853767D02*
Y-535500D01*
X-851767D01*
X-851100Y-535850D01*
X-850600Y-536667D01*
X-850433Y-537600D01*
X-850600Y-538533D01*
X-851017Y-539233D01*
X-851767Y-539584D01*
X-853767D01*
G01X-845300Y-542500D02*
X-845967Y-542383D01*
X-846550Y-541917D01*
X-847050Y-541217D01*
X-847383Y-540400D01*
X-847550Y-539467D01*
Y-538533D01*
X-847383Y-537600D01*
X-847050Y-536783D01*
X-846550Y-536083D01*
X-845967Y-535617D01*
X-845300Y-535500D01*
X-844633Y-535617D01*
X-844050Y-536083D01*
X-843550Y-536783D01*
X-843217Y-537600D01*
X-843050Y-538533D01*
Y-539467D01*
X-843217Y-540400D01*
X-843550Y-541217D01*
X-844050Y-541917D01*
X-844633Y-542383D01*
X-845300Y-542500D01*
G01X-840167D02*
Y-535500D01*
X-838083D01*
X-837417Y-535850D01*
X-837000Y-536317D01*
X-836833Y-537250D01*
X-837000Y-538183D01*
X-837500Y-538767D01*
X-838083Y-539117D01*
X-840167D01*
G01X-838083D02*
X-836833Y-542500D01*
G01X-833783D02*
X-831700Y-535500D01*
X-829617Y-542500D01*
G01X-830367Y-540050D02*
X-833033D01*
G01X-824900Y-535500D02*
Y-542500D01*
G01X-826817Y-535500D02*
X-822983D01*
G01X-819100D02*
X-817100D01*
G01X-818100D02*
Y-542500D01*
G01X-819100D02*
X-817100D01*
G01X-811300D02*
X-811967Y-542383D01*
X-812550Y-541917D01*
X-813050Y-541217D01*
X-813383Y-540400D01*
X-813550Y-539467D01*
Y-538533D01*
X-813383Y-537600D01*
X-813050Y-536783D01*
X-812550Y-536083D01*
X-811967Y-535617D01*
X-811300Y-535500D01*
X-810633Y-535617D01*
X-810050Y-536083D01*
X-809550Y-536783D01*
X-809217Y-537600D01*
X-809050Y-538533D01*
Y-539467D01*
X-809217Y-540400D01*
X-809550Y-541217D01*
X-810050Y-541917D01*
X-810633Y-542383D01*
X-811300Y-542500D01*
G01X-806417D02*
Y-535500D01*
X-802583Y-542500D01*
Y-535500D01*
G01X-797700Y-542733D02*
X-797867Y-542617D01*
Y-542383D01*
X-797700Y-542267D01*
X-797533Y-542383D01*
Y-542617D01*
X-797700Y-542733D01*
G01X-784100Y-535500D02*
Y-542500D01*
G01X-786017Y-535500D02*
X-782183D01*
G01X-779050Y-542500D02*
Y-535500D01*
G01X-775550D02*
Y-542500D01*
G01Y-539000D02*
X-779050D01*
G01X-771500Y-535500D02*
X-769500D01*
G01X-770500D02*
Y-542500D01*
G01X-771500D02*
X-769500D01*
G01X-765450Y-541567D02*
X-764783Y-542150D01*
X-764033Y-542500D01*
X-763367D01*
X-762700Y-542150D01*
X-762200Y-541567D01*
X-761950Y-540750D01*
X-762117Y-539933D01*
X-762533Y-539233D01*
X-763283Y-538767D01*
X-764283Y-538533D01*
X-764867Y-538067D01*
X-765117Y-537250D01*
X-764950Y-536433D01*
X-764533Y-535850D01*
X-763950Y-535500D01*
X-763367D01*
X-762783Y-535733D01*
X-762283Y-536317D01*
G01X-751933Y-542500D02*
Y-535500D01*
X-750267D01*
X-749600Y-535850D01*
X-749100Y-536317D01*
X-748683Y-537017D01*
X-748350Y-537833D01*
X-748267Y-539000D01*
X-748350Y-540167D01*
X-748683Y-540983D01*
X-749100Y-541684D01*
X-749600Y-542150D01*
X-750267Y-542500D01*
X-751933D01*
G01X-744967D02*
Y-535500D01*
X-742883D01*
X-742217Y-535850D01*
X-741800Y-536317D01*
X-741633Y-537250D01*
X-741800Y-538183D01*
X-742300Y-538767D01*
X-742883Y-539117D01*
X-744967D01*
G01X-742883D02*
X-741633Y-542500D01*
G01X-738583D02*
X-736500Y-535500D01*
X-734417Y-542500D01*
G01X-735167Y-540050D02*
X-737833D01*
G01X-732200Y-535500D02*
X-731033Y-542500D01*
X-729700Y-535500D01*
X-728367Y-542500D01*
X-727200Y-535500D01*
G01X-723900D02*
X-721900D01*
G01X-722900D02*
Y-542500D01*
G01X-723900D02*
X-721900D01*
G01X-718017D02*
Y-535500D01*
X-714183Y-542500D01*
Y-535500D01*
G01X-708800Y-539000D02*
X-707133D01*
Y-541100D01*
X-707633Y-541800D01*
X-708217Y-542267D01*
X-709050Y-542500D01*
X-709883Y-542267D01*
X-710467Y-541800D01*
X-710967Y-541100D01*
X-711300Y-540283D01*
X-711467Y-539350D01*
Y-538533D01*
X-711300Y-537833D01*
X-710967Y-537017D01*
X-710467Y-536317D01*
X-709967Y-535850D01*
X-709300Y-535500D01*
X-708717D01*
X-708050Y-535733D01*
X-707550Y-536200D01*
G01X-696700Y-535500D02*
X-694700D01*
G01X-695700D02*
Y-542500D01*
G01X-696700D02*
X-694700D01*
G01X-690650Y-541567D02*
X-689983Y-542150D01*
X-689233Y-542500D01*
X-688567D01*
X-687900Y-542150D01*
X-687400Y-541567D01*
X-687150Y-540750D01*
X-687317Y-539933D01*
X-687733Y-539233D01*
X-688483Y-538767D01*
X-689483Y-538533D01*
X-690067Y-538067D01*
X-690317Y-537250D01*
X-690150Y-536433D01*
X-689733Y-535850D01*
X-689150Y-535500D01*
X-688567D01*
X-687983Y-535733D01*
X-687483Y-536317D01*
G01X-676967Y-542500D02*
Y-535500D01*
X-674883D01*
X-674217Y-535850D01*
X-673800Y-536317D01*
X-673633Y-537250D01*
X-673800Y-538183D01*
X-674300Y-538767D01*
X-674883Y-539117D01*
X-676967D01*
G01X-674883D02*
X-673633Y-542500D01*
G01X-666833D02*
X-670167D01*
Y-535500D01*
X-666833D01*
G01X-668167Y-538883D02*
X-670167D01*
G01X-659867Y-536083D02*
X-660367Y-535733D01*
X-660950Y-535500D01*
X-661617D01*
X-662367Y-535850D01*
X-662950Y-536433D01*
X-663367Y-537133D01*
X-663700Y-538300D01*
X-663783Y-539350D01*
X-663617Y-540400D01*
X-663367Y-541100D01*
X-662867Y-541800D01*
X-662283Y-542267D01*
X-661700Y-542500D01*
X-661117D01*
X-660533Y-542267D01*
X-660033Y-541917D01*
X-659617Y-541450D01*
G01X-653233Y-542500D02*
X-656567D01*
Y-535500D01*
X-653233D01*
G01X-654567Y-538883D02*
X-656567D01*
G01X-649100Y-535500D02*
X-647100D01*
G01X-648100D02*
Y-542500D01*
G01X-649100D02*
X-647100D01*
G01X-643383Y-535500D02*
X-641300Y-542500D01*
X-639217Y-535500D01*
G01X-632833Y-542500D02*
X-636167D01*
Y-535500D01*
X-632833D01*
G01X-634167Y-538883D02*
X-636167D01*
G01X-629533Y-542500D02*
Y-535500D01*
X-627867D01*
X-627200Y-535850D01*
X-626700Y-536317D01*
X-626283Y-537017D01*
X-625950Y-537833D01*
X-625867Y-539000D01*
X-625950Y-540167D01*
X-626283Y-540983D01*
X-626700Y-541684D01*
X-627200Y-542150D01*
X-627867Y-542500D01*
X-629533D01*
G01X-615100Y-535500D02*
X-613100D01*
G01X-614100D02*
Y-542500D01*
G01X-615100D02*
X-613100D01*
G01X-609217D02*
Y-535500D01*
X-605383Y-542500D01*
Y-535500D01*
G01X-872500Y-520500D02*
Y-527500D01*
G01X-874417Y-520500D02*
X-870583D01*
G01X-867450Y-527500D02*
Y-520500D01*
G01X-863950D02*
Y-527500D01*
G01Y-524000D02*
X-867450D01*
G01X-857233Y-527500D02*
X-860567D01*
Y-520500D01*
X-857233D01*
G01X-858567Y-523883D02*
X-860567D01*
G01X-846967Y-527500D02*
Y-520500D01*
X-844967D01*
X-844300Y-520850D01*
X-843800Y-521667D01*
X-843633Y-522600D01*
X-843800Y-523533D01*
X-844217Y-524233D01*
X-844967Y-524584D01*
X-846967D01*
G01X-840167Y-527500D02*
Y-520500D01*
X-838083D01*
X-837417Y-520850D01*
X-837000Y-521317D01*
X-836833Y-522250D01*
X-837000Y-523183D01*
X-837500Y-523767D01*
X-838083Y-524117D01*
X-840167D01*
G01X-838083D02*
X-836833Y-527500D01*
G01X-831700D02*
X-832367Y-527383D01*
X-832950Y-526917D01*
X-833450Y-526217D01*
X-833783Y-525400D01*
X-833950Y-524467D01*
Y-523533D01*
X-833783Y-522600D01*
X-833450Y-521783D01*
X-832950Y-521083D01*
X-832367Y-520617D01*
X-831700Y-520500D01*
X-831033Y-520617D01*
X-830450Y-521083D01*
X-829950Y-521783D01*
X-829617Y-522600D01*
X-829450Y-523533D01*
Y-524467D01*
X-829617Y-525400D01*
X-829950Y-526217D01*
X-830450Y-526917D01*
X-831033Y-527383D01*
X-831700Y-527500D01*
G01X-826567D02*
Y-520500D01*
X-824567D01*
X-823900Y-520850D01*
X-823400Y-521667D01*
X-823233Y-522600D01*
X-823400Y-523533D01*
X-823817Y-524233D01*
X-824567Y-524584D01*
X-826567D01*
G01X-819767Y-527500D02*
Y-520500D01*
X-817683D01*
X-817017Y-520850D01*
X-816600Y-521317D01*
X-816433Y-522250D01*
X-816600Y-523183D01*
X-817100Y-523767D01*
X-817683Y-524117D01*
X-819767D01*
G01X-817683D02*
X-816433Y-527500D01*
G01X-812300Y-520500D02*
X-810300D01*
G01X-811300D02*
Y-527500D01*
G01X-812300D02*
X-810300D01*
G01X-802833D02*
X-806167D01*
Y-520500D01*
X-802833D01*
G01X-804167Y-523883D02*
X-806167D01*
G01X-797700Y-520500D02*
Y-527500D01*
G01X-799617Y-520500D02*
X-795783D01*
G01X-792983Y-527500D02*
X-790900Y-520500D01*
X-788817Y-527500D01*
G01X-789567Y-525050D02*
X-792233D01*
G01X-785767Y-527500D02*
Y-520500D01*
X-783683D01*
X-783017Y-520850D01*
X-782600Y-521317D01*
X-782433Y-522250D01*
X-782600Y-523183D01*
X-783100Y-523767D01*
X-783683Y-524117D01*
X-785767D01*
G01X-783683D02*
X-782433Y-527500D01*
G01X-777300D02*
Y-524350D01*
X-778967Y-520500D01*
G01X-775633D02*
X-777300Y-524350D01*
G01X-765367Y-527500D02*
Y-520500D01*
X-763367D01*
X-762700Y-520850D01*
X-762200Y-521667D01*
X-762033Y-522600D01*
X-762200Y-523533D01*
X-762617Y-524233D01*
X-763367Y-524584D01*
X-765367D01*
G01X-758567Y-527500D02*
Y-520500D01*
X-756483D01*
X-755817Y-520850D01*
X-755400Y-521317D01*
X-755233Y-522250D01*
X-755400Y-523183D01*
X-755900Y-523767D01*
X-756483Y-524117D01*
X-758567D01*
G01X-756483D02*
X-755233Y-527500D01*
G01X-750100D02*
X-750767Y-527383D01*
X-751350Y-526917D01*
X-751850Y-526217D01*
X-752183Y-525400D01*
X-752350Y-524467D01*
Y-523533D01*
X-752183Y-522600D01*
X-751850Y-521783D01*
X-751350Y-521083D01*
X-750767Y-520617D01*
X-750100Y-520500D01*
X-749433Y-520617D01*
X-748850Y-521083D01*
X-748350Y-521783D01*
X-748017Y-522600D01*
X-747850Y-523533D01*
Y-524467D01*
X-748017Y-525400D01*
X-748350Y-526217D01*
X-748850Y-526917D01*
X-749433Y-527383D01*
X-750100Y-527500D01*
G01X-744967D02*
Y-520500D01*
X-742967D01*
X-742300Y-520850D01*
X-741800Y-521667D01*
X-741633Y-522600D01*
X-741800Y-523533D01*
X-742217Y-524233D01*
X-742967Y-524584D01*
X-744967D01*
G01X-734833Y-527500D02*
X-738167D01*
Y-520500D01*
X-734833D01*
G01X-736167Y-523883D02*
X-738167D01*
G01X-731367Y-527500D02*
Y-520500D01*
X-729283D01*
X-728617Y-520850D01*
X-728200Y-521317D01*
X-728033Y-522250D01*
X-728200Y-523183D01*
X-728700Y-523767D01*
X-729283Y-524117D01*
X-731367D01*
G01X-729283D02*
X-728033Y-527500D01*
G01X-722900Y-520500D02*
Y-527500D01*
G01X-724817Y-520500D02*
X-720983D01*
G01X-716100Y-527500D02*
Y-524350D01*
X-717767Y-520500D01*
G01X-714433D02*
X-716100Y-524350D01*
G01X-702500Y-527500D02*
X-703167Y-527383D01*
X-703750Y-526917D01*
X-704250Y-526217D01*
X-704583Y-525400D01*
X-704750Y-524467D01*
Y-523533D01*
X-704583Y-522600D01*
X-704250Y-521783D01*
X-703750Y-521083D01*
X-703167Y-520617D01*
X-702500Y-520500D01*
X-701833Y-520617D01*
X-701250Y-521083D01*
X-700750Y-521783D01*
X-700417Y-522600D01*
X-700250Y-523533D01*
Y-524467D01*
X-700417Y-525400D01*
X-700750Y-526217D01*
X-701250Y-526917D01*
X-701833Y-527383D01*
X-702500Y-527500D01*
G01X-697283D02*
Y-520500D01*
X-694117D01*
G01X-695283Y-523883D02*
X-697283D01*
G01X-684267Y-527500D02*
Y-520500D01*
X-682100Y-526333D01*
X-679933Y-520500D01*
Y-527500D01*
G01X-676300Y-520500D02*
X-674300D01*
G01X-675300D02*
Y-527500D01*
G01X-676300D02*
X-674300D01*
G01X-666667Y-521083D02*
X-667167Y-520733D01*
X-667750Y-520500D01*
X-668417D01*
X-669167Y-520850D01*
X-669750Y-521433D01*
X-670167Y-522133D01*
X-670500Y-523300D01*
X-670583Y-524350D01*
X-670417Y-525400D01*
X-670167Y-526100D01*
X-669667Y-526800D01*
X-669083Y-527267D01*
X-668500Y-527500D01*
X-667917D01*
X-667333Y-527267D01*
X-666833Y-526917D01*
X-666417Y-526450D01*
G01X-663367Y-527500D02*
Y-520500D01*
X-661283D01*
X-660617Y-520850D01*
X-660200Y-521317D01*
X-660033Y-522250D01*
X-660200Y-523183D01*
X-660700Y-523767D01*
X-661283Y-524117D01*
X-663367D01*
G01X-661283D02*
X-660033Y-527500D01*
G01X-654900D02*
X-655567Y-527383D01*
X-656150Y-526917D01*
X-656650Y-526217D01*
X-656983Y-525400D01*
X-657150Y-524467D01*
Y-523533D01*
X-656983Y-522600D01*
X-656650Y-521783D01*
X-656150Y-521083D01*
X-655567Y-520617D01*
X-654900Y-520500D01*
X-654233Y-520617D01*
X-653650Y-521083D01*
X-653150Y-521783D01*
X-652817Y-522600D01*
X-652650Y-523533D01*
Y-524467D01*
X-652817Y-525400D01*
X-653150Y-526217D01*
X-653650Y-526917D01*
X-654233Y-527383D01*
X-654900Y-527500D01*
G01X-649850Y-526567D02*
X-649183Y-527150D01*
X-648433Y-527500D01*
X-647767D01*
X-647100Y-527150D01*
X-646600Y-526567D01*
X-646350Y-525750D01*
X-646517Y-524933D01*
X-646933Y-524233D01*
X-647683Y-523767D01*
X-648683Y-523533D01*
X-649267Y-523067D01*
X-649517Y-522250D01*
X-649350Y-521433D01*
X-648933Y-520850D01*
X-648350Y-520500D01*
X-647767D01*
X-647183Y-520733D01*
X-646683Y-521317D01*
G01X-641300Y-527500D02*
X-641967Y-527383D01*
X-642550Y-526917D01*
X-643050Y-526217D01*
X-643383Y-525400D01*
X-643550Y-524467D01*
Y-523533D01*
X-643383Y-522600D01*
X-643050Y-521783D01*
X-642550Y-521083D01*
X-641967Y-520617D01*
X-641300Y-520500D01*
X-640633Y-520617D01*
X-640050Y-521083D01*
X-639550Y-521783D01*
X-639217Y-522600D01*
X-639050Y-523533D01*
Y-524467D01*
X-639217Y-525400D01*
X-639550Y-526217D01*
X-640050Y-526917D01*
X-640633Y-527383D01*
X-641300Y-527500D01*
G01X-636083D02*
Y-520500D01*
X-632917D01*
G01X-634083Y-523883D02*
X-636083D01*
G01X-627700Y-520500D02*
Y-527500D01*
G01X-629617Y-520500D02*
X-625783D01*
G01X-872500Y-505500D02*
Y-512500D01*
G01X-874417Y-505500D02*
X-870583D01*
G01X-867450Y-512500D02*
Y-505500D01*
G01X-863950D02*
Y-512500D01*
G01Y-509000D02*
X-867450D01*
G01X-859900Y-505500D02*
X-857900D01*
G01X-858900D02*
Y-512500D01*
G01X-859900D02*
X-857900D01*
G01X-853850Y-511567D02*
X-853183Y-512150D01*
X-852433Y-512500D01*
X-851767D01*
X-851100Y-512150D01*
X-850600Y-511567D01*
X-850350Y-510750D01*
X-850517Y-509933D01*
X-850933Y-509233D01*
X-851683Y-508767D01*
X-852683Y-508533D01*
X-853267Y-508067D01*
X-853517Y-507250D01*
X-853350Y-506433D01*
X-852933Y-505850D01*
X-852350Y-505500D01*
X-851767D01*
X-851183Y-505733D01*
X-850683Y-506317D01*
G01X-840333Y-512500D02*
Y-505500D01*
X-838667D01*
X-838000Y-505850D01*
X-837500Y-506317D01*
X-837083Y-507017D01*
X-836750Y-507833D01*
X-836667Y-509000D01*
X-836750Y-510167D01*
X-837083Y-510983D01*
X-837500Y-511684D01*
X-838000Y-512150D01*
X-838667Y-512500D01*
X-840333D01*
G01X-833367D02*
Y-505500D01*
X-831283D01*
X-830617Y-505850D01*
X-830200Y-506317D01*
X-830033Y-507250D01*
X-830200Y-508183D01*
X-830700Y-508767D01*
X-831283Y-509117D01*
X-833367D01*
G01X-831283D02*
X-830033Y-512500D01*
G01X-826983D02*
X-824900Y-505500D01*
X-822817Y-512500D01*
G01X-823567Y-510050D02*
X-826233D01*
G01X-820600Y-505500D02*
X-819433Y-512500D01*
X-818100Y-505500D01*
X-816767Y-512500D01*
X-815600Y-505500D01*
G01X-812300D02*
X-810300D01*
G01X-811300D02*
Y-512500D01*
G01X-812300D02*
X-810300D01*
G01X-806417D02*
Y-505500D01*
X-802583Y-512500D01*
Y-505500D01*
G01X-797200Y-509000D02*
X-795533D01*
Y-511100D01*
X-796033Y-511800D01*
X-796617Y-512267D01*
X-797450Y-512500D01*
X-798283Y-512267D01*
X-798867Y-511800D01*
X-799367Y-511100D01*
X-799700Y-510283D01*
X-799867Y-509350D01*
Y-508533D01*
X-799700Y-507833D01*
X-799367Y-507017D01*
X-798867Y-506317D01*
X-798367Y-505850D01*
X-797700Y-505500D01*
X-797117D01*
X-796450Y-505733D01*
X-795950Y-506200D01*
G01X-782267Y-506083D02*
X-782767Y-505733D01*
X-783350Y-505500D01*
X-784017D01*
X-784767Y-505850D01*
X-785350Y-506433D01*
X-785767Y-507133D01*
X-786100Y-508300D01*
X-786183Y-509350D01*
X-786017Y-510400D01*
X-785767Y-511100D01*
X-785267Y-511800D01*
X-784683Y-512267D01*
X-784100Y-512500D01*
X-783517D01*
X-782933Y-512267D01*
X-782433Y-511917D01*
X-782017Y-511450D01*
G01X-777300Y-512500D02*
X-777967Y-512383D01*
X-778550Y-511917D01*
X-779050Y-511217D01*
X-779383Y-510400D01*
X-779550Y-509467D01*
Y-508533D01*
X-779383Y-507600D01*
X-779050Y-506783D01*
X-778550Y-506083D01*
X-777967Y-505617D01*
X-777300Y-505500D01*
X-776633Y-505617D01*
X-776050Y-506083D01*
X-775550Y-506783D01*
X-775217Y-507600D01*
X-775050Y-508533D01*
Y-509467D01*
X-775217Y-510400D01*
X-775550Y-511217D01*
X-776050Y-511917D01*
X-776633Y-512383D01*
X-777300Y-512500D01*
G01X-772417D02*
Y-505500D01*
X-768583Y-512500D01*
Y-505500D01*
G01X-763700D02*
Y-512500D01*
G01X-765617Y-505500D02*
X-761783D01*
G01X-758983Y-512500D02*
X-756900Y-505500D01*
X-754817Y-512500D01*
G01X-755567Y-510050D02*
X-758233D01*
G01X-751100Y-505500D02*
X-749100D01*
G01X-750100D02*
Y-512500D01*
G01X-751100D02*
X-749100D01*
G01X-745217D02*
Y-505500D01*
X-741383Y-512500D01*
Y-505500D01*
G01X-738250Y-511567D02*
X-737583Y-512150D01*
X-736833Y-512500D01*
X-736167D01*
X-735500Y-512150D01*
X-735000Y-511567D01*
X-734750Y-510750D01*
X-734917Y-509933D01*
X-735333Y-509233D01*
X-736083Y-508767D01*
X-737083Y-508533D01*
X-737667Y-508067D01*
X-737917Y-507250D01*
X-737750Y-506433D01*
X-737333Y-505850D01*
X-736750Y-505500D01*
X-736167D01*
X-735583Y-505733D01*
X-735083Y-506317D01*
G01X-723900Y-505500D02*
X-721900D01*
G01X-722900D02*
Y-512500D01*
G01X-723900D02*
X-721900D01*
G01X-718017D02*
Y-505500D01*
X-714183Y-512500D01*
Y-505500D01*
G01X-710883Y-512500D02*
Y-505500D01*
X-707717D01*
G01X-708883Y-508883D02*
X-710883D01*
G01X-702500Y-512500D02*
X-703167Y-512383D01*
X-703750Y-511917D01*
X-704250Y-511217D01*
X-704583Y-510400D01*
X-704750Y-509467D01*
Y-508533D01*
X-704583Y-507600D01*
X-704250Y-506783D01*
X-703750Y-506083D01*
X-703167Y-505617D01*
X-702500Y-505500D01*
X-701833Y-505617D01*
X-701250Y-506083D01*
X-700750Y-506783D01*
X-700417Y-507600D01*
X-700250Y-508533D01*
Y-509467D01*
X-700417Y-510400D01*
X-700750Y-511217D01*
X-701250Y-511917D01*
X-701833Y-512383D01*
X-702500Y-512500D01*
G01X-697367D02*
Y-505500D01*
X-695283D01*
X-694617Y-505850D01*
X-694200Y-506317D01*
X-694033Y-507250D01*
X-694200Y-508183D01*
X-694700Y-508767D01*
X-695283Y-509117D01*
X-697367D01*
G01X-695283D02*
X-694033Y-512500D01*
G01X-691067D02*
Y-505500D01*
X-688900Y-511333D01*
X-686733Y-505500D01*
Y-512500D01*
G01X-684183D02*
X-682100Y-505500D01*
X-680017Y-512500D01*
G01X-680767Y-510050D02*
X-683433D01*
G01X-675300Y-505500D02*
Y-512500D01*
G01X-677217Y-505500D02*
X-673383D01*
G01X-669500D02*
X-667500D01*
G01X-668500D02*
Y-512500D01*
G01X-669500D02*
X-667500D01*
G01X-661700D02*
X-662367Y-512383D01*
X-662950Y-511917D01*
X-663450Y-511217D01*
X-663783Y-510400D01*
X-663950Y-509467D01*
Y-508533D01*
X-663783Y-507600D01*
X-663450Y-506783D01*
X-662950Y-506083D01*
X-662367Y-505617D01*
X-661700Y-505500D01*
X-661033Y-505617D01*
X-660450Y-506083D01*
X-659950Y-506783D01*
X-659617Y-507600D01*
X-659450Y-508533D01*
Y-509467D01*
X-659617Y-510400D01*
X-659950Y-511217D01*
X-660450Y-511917D01*
X-661033Y-512383D01*
X-661700Y-512500D01*
G01X-656817D02*
Y-505500D01*
X-652983Y-512500D01*
Y-505500D01*
G01X-643800D02*
X-642633Y-512500D01*
X-641300Y-505500D01*
X-639967Y-512500D01*
X-638800Y-505500D01*
G01X-636250Y-512500D02*
Y-505500D01*
G01X-632750D02*
Y-512500D01*
G01Y-509000D02*
X-636250D01*
G01X-628700Y-505500D02*
X-626700D01*
G01X-627700D02*
Y-512500D01*
G01X-628700D02*
X-626700D01*
G01X-619067Y-506083D02*
X-619567Y-505733D01*
X-620150Y-505500D01*
X-620817D01*
X-621567Y-505850D01*
X-622150Y-506433D01*
X-622567Y-507133D01*
X-622900Y-508300D01*
X-622983Y-509350D01*
X-622817Y-510400D01*
X-622567Y-511100D01*
X-622067Y-511800D01*
X-621483Y-512267D01*
X-620900Y-512500D01*
X-620317D01*
X-619733Y-512267D01*
X-619233Y-511917D01*
X-618817Y-511450D01*
G01X-615850Y-512500D02*
Y-505500D01*
G01X-612350D02*
Y-512500D01*
G01Y-509000D02*
X-615850D01*
G01X-601500Y-505500D02*
X-599500D01*
G01X-600500D02*
Y-512500D01*
G01X-601500D02*
X-599500D01*
G01X-595450Y-511567D02*
X-594783Y-512150D01*
X-594033Y-512500D01*
X-593367D01*
X-592700Y-512150D01*
X-592200Y-511567D01*
X-591950Y-510750D01*
X-592117Y-509933D01*
X-592533Y-509233D01*
X-593283Y-508767D01*
X-594283Y-508533D01*
X-594867Y-508067D01*
X-595117Y-507250D01*
X-594950Y-506433D01*
X-594533Y-505850D01*
X-593950Y-505500D01*
X-593367D01*
X-592783Y-505733D01*
X-592283Y-506317D01*
G01X-858133Y-452500D02*
Y-445500D01*
X-856467D01*
X-855800Y-445850D01*
X-855300Y-446317D01*
X-854883Y-447017D01*
X-854550Y-447833D01*
X-854467Y-449000D01*
X-854550Y-450167D01*
X-854883Y-450983D01*
X-855300Y-451684D01*
X-855800Y-452150D01*
X-856467Y-452500D01*
X-858133D01*
G01X-847833D02*
X-851167D01*
Y-445500D01*
X-847833D01*
G01X-849167Y-448883D02*
X-851167D01*
G01X-844450Y-451567D02*
X-843783Y-452150D01*
X-843033Y-452500D01*
X-842367D01*
X-841700Y-452150D01*
X-841200Y-451567D01*
X-840950Y-450750D01*
X-841117Y-449933D01*
X-841533Y-449233D01*
X-842283Y-448767D01*
X-843283Y-448533D01*
X-843867Y-448067D01*
X-844117Y-447250D01*
X-843950Y-446433D01*
X-843533Y-445850D01*
X-842950Y-445500D01*
X-842367D01*
X-841783Y-445733D01*
X-841283Y-446317D01*
G01X-836900Y-445500D02*
X-834900D01*
G01X-835900D02*
Y-452500D01*
G01X-836900D02*
X-834900D01*
G01X-828600Y-449000D02*
X-826933D01*
Y-451100D01*
X-827433Y-451800D01*
X-828017Y-452267D01*
X-828850Y-452500D01*
X-829683Y-452267D01*
X-830267Y-451800D01*
X-830767Y-451100D01*
X-831100Y-450283D01*
X-831267Y-449350D01*
Y-448533D01*
X-831100Y-447833D01*
X-830767Y-447017D01*
X-830267Y-446317D01*
X-829767Y-445850D01*
X-829100Y-445500D01*
X-828517D01*
X-827850Y-445733D01*
X-827350Y-446200D01*
G01X-824217Y-452500D02*
Y-445500D01*
X-820383Y-452500D01*
Y-445500D01*
G01X-813833Y-452500D02*
X-817167D01*
Y-445500D01*
X-813833D01*
G01X-815167Y-448883D02*
X-817167D01*
G01X-810367Y-452500D02*
Y-445500D01*
X-808283D01*
X-807617Y-445850D01*
X-807200Y-446317D01*
X-807033Y-447250D01*
X-807200Y-448183D01*
X-807700Y-448767D01*
X-808283Y-449117D01*
X-810367D01*
G01X-808283D02*
X-807033Y-452500D01*
G01X-858133D02*
Y-445500D01*
X-856467D01*
X-855800Y-445850D01*
X-855300Y-446317D01*
X-854883Y-447017D01*
X-854550Y-447833D01*
X-854467Y-449000D01*
X-854550Y-450167D01*
X-854883Y-450983D01*
X-855300Y-451684D01*
X-855800Y-452150D01*
X-856467Y-452500D01*
X-858133D01*
G01X-847833D02*
X-851167D01*
Y-445500D01*
X-847833D01*
G01X-849167Y-448883D02*
X-851167D01*
G01X-844450Y-451567D02*
X-843783Y-452150D01*
X-843033Y-452500D01*
X-842367D01*
X-841700Y-452150D01*
X-841200Y-451567D01*
X-840950Y-450750D01*
X-841117Y-449933D01*
X-841533Y-449233D01*
X-842283Y-448767D01*
X-843283Y-448533D01*
X-843867Y-448067D01*
X-844117Y-447250D01*
X-843950Y-446433D01*
X-843533Y-445850D01*
X-842950Y-445500D01*
X-842367D01*
X-841783Y-445733D01*
X-841283Y-446317D01*
G01X-836900Y-445500D02*
X-834900D01*
G01X-835900D02*
Y-452500D01*
G01X-836900D02*
X-834900D01*
G01X-828600Y-449000D02*
X-826933D01*
Y-451100D01*
X-827433Y-451800D01*
X-828017Y-452267D01*
X-828850Y-452500D01*
X-829683Y-452267D01*
X-830267Y-451800D01*
X-830767Y-451100D01*
X-831100Y-450283D01*
X-831267Y-449350D01*
Y-448533D01*
X-831100Y-447833D01*
X-830767Y-447017D01*
X-830267Y-446317D01*
X-829767Y-445850D01*
X-829100Y-445500D01*
X-828517D01*
X-827850Y-445733D01*
X-827350Y-446200D01*
G01X-824217Y-452500D02*
Y-445500D01*
X-820383Y-452500D01*
Y-445500D01*
G01X-813833Y-452500D02*
X-817167D01*
Y-445500D01*
X-813833D01*
G01X-815167Y-448883D02*
X-817167D01*
G01X-810367Y-452500D02*
Y-445500D01*
X-808283D01*
X-807617Y-445850D01*
X-807200Y-446317D01*
X-807033Y-447250D01*
X-807200Y-448183D01*
X-807700Y-448767D01*
X-808283Y-449117D01*
X-810367D01*
G01X-808283D02*
X-807033Y-452500D01*
G01X-642033Y-455000D02*
Y-448000D01*
X-640367D01*
X-639700Y-448350D01*
X-639200Y-448817D01*
X-638783Y-449517D01*
X-638450Y-450333D01*
X-638367Y-451500D01*
X-638450Y-452667D01*
X-638783Y-453483D01*
X-639200Y-454184D01*
X-639700Y-454650D01*
X-640367Y-455000D01*
X-642033D01*
G01X-635483D02*
X-633400Y-448000D01*
X-631317Y-455000D01*
G01X-632067Y-452550D02*
X-634733D01*
G01X-626600Y-448000D02*
Y-455000D01*
G01X-628517Y-448000D02*
X-624683D01*
G01X-618133Y-455000D02*
X-621467D01*
Y-448000D01*
X-618133D01*
G01X-619467Y-451383D02*
X-621467D01*
G54D18*
G01X-1020800Y-457700D02*
G02X-1020300Y-458200I0J-500D01*
G01Y-458400D01*
G02X-1020900Y-459000I-600J0D01*
G01X-1021300D01*
G01X-1021800Y-460500D02*
Y-457700D01*
X-1020600D01*
G01X-1018340Y-459100D02*
G03I-2660J0D01*
G01X-1020700D02*
X-1020200Y-460500D01*
M02*
